FILE_TYPE = MACRO_DRAWING;
SET COLOR_WIRE YELLOW;
SET COLOR_PROP ORANGE;
SET COLOR_DOT WHITE;
SET COLOR_ARC YELLOW;
SET COLOR_BODY GREEN;
SET COLOR_NOTE PURPLE;
SET PROP_DISPLAY VALUE;
SET PAGE_NUMBER P301;
FORCEADD UNIVERSAL_GND..1
(-2875 -2350);
FORCEPROP 3 LASTPIN (-2875 -2300) SIG_NAME AGND_HSC\g
J 0
(-2865 -2290);
DISPLAY 0.659574 (-2865 -2290);
PAINT MONO (-2865 -2290);
DISPLAY INVISIBLE (-2865 -2290);
FORCEPROP 1 LAST HDL_POWER AGND_HSC
J 1
(-2850 -2425);
DISPLAY 0.723404 (-2850 -2425);
PAINT GREEN (-2850 -2425);
FORCEPROP 2 LAST CDS_LIB logical_power
J 0
(-2875 -2350);
DISPLAY INVISIBLE (-2875 -2350);
FORCEPROP 1 LAST PATH I1
J 0
(-2800 -2350);
DISPLAY 0.872340 (-2800 -2350);
PAINT AQUA (-2800 -2350);
DISPLAY INVISIBLE (-2800 -2350);
FORCEADD OFFPAGE..4
R 2
(-2275 -1375);
FORCEPROP 2 LAST $XR2 303 
J 0
(-2767 -1375);
DISPLAY 0.638298 (-2767 -1375);
PAINT MONO (-2767 -1375);
FORCEPROP 2 LAST $XR1 302 
J 0
(-2647 -1375);
DISPLAY 0.638298 (-2647 -1375);
PAINT MONO (-2647 -1375);
FORCEPROP 2 LAST $XR0 301 
J 0
(-2527 -1375);
DISPLAY 0.638298 (-2527 -1375);
PAINT MONO (-2527 -1375);
FORCEPROP 2 LAST CDS_LIB standard
J 0
(-2275 -1375);
DISPLAY INVISIBLE (-2275 -1375);
FORCEPROP 1 LAST OFFPAGE TRUE
J 2
(-2600 -1500);
DISPLAY 0.872340 (-2600 -1500);
PAINT GREEN (-2600 -1500);
DISPLAY INVISIBLE (-2600 -1500);
FORCEPROP 1 LAST COMMENT_BODY TRUE
J 2
(-2250 -1475);
DISPLAY 0.872340 (-2250 -1475);
PAINT GREEN (-2250 -1475);
DISPLAY INVISIBLE (-2250 -1475);
FORCEPROP 2 LAST PATH I10
J 0
(-2525 -1325);
DISPLAY 1.021277 (-2525 -1325);
DISPLAY INVISIBLE (-2525 -1325);
FORCEADD Q_CAP..1
(-2200 -2025);
FORCEPROP 1 LAST PART_NUMBER CH21006KB16
J 0
(-2125 -2125);
DISPLAY 0.723404 (-2125 -2125);
PAINT WHITE (-2125 -2125);
DISPLAY INVISIBLE (-2125 -2125);
FORCEPROP 1 LAST VALUE 1NF
J 0
(-2125 -1975);
DISPLAY 0.723404 (-2125 -1975);
PAINT SKYBLUE (-2125 -1975);
FORCEPROP 1 LAST VOLTAGE 50V
J 0
(-2125 -2025);
DISPLAY 0.723404 (-2125 -2025);
PAINT SKYBLUE (-2125 -2025);
FORCEPROP 1 LAST MATERIAL EMPTY
J 0
(-2125 -2075);
DISPLAY 0.723404 (-2125 -2075);
PAINT RED (-2125 -2075);
FORCEPROP 1 LAST PACK_TYPE 0402
J 0
(-2125 -2175);
DISPLAY 0.723404 (-2125 -2175);
PAINT SKYBLUE (-2125 -2175);
FORCEPROP 1 LAST LOCATION PC2348
J 0
(-2125 -1925);
DISPLAY 0.638298 (-2125 -1925);
PAINT AQUA (-2125 -1925);
FORCEPROP 1 LASTPIN (-2200 -1925) $PN 1
J 0
(-2190 -1945);
DISPLAY 0.787234 (-2190 -1945);
PAINT MONO (-2190 -1945);
FORCEPROP 1 LASTPIN (-2200 -2125) $PN 2
J 0
(-2190 -2145);
DISPLAY 0.787234 (-2190 -2145);
PAINT MONO (-2190 -2145);
FORCEPROP 1 LAST TOLERANCE 10%
J 0
(-2150 -2075);
DISPLAY 0.978723 (-2150 -2075);
PAINT SKYBLUE (-2150 -2075);
DISPLAY INVISIBLE (-2150 -2075);
FORCEPROP 2 LAST CDS_LIB pure_quanta
J 0
(-2200 -2025);
DISPLAY INVISIBLE (-2200 -2025);
FORCEPROP 1 LAST PATH I11
J 0
(-2150 -1875);
DISPLAY 0.978723 (-2150 -1875);
PAINT WHITE (-2150 -1875);
DISPLAY INVISIBLE (-2150 -1875);
FORCEPROP 0 LAST $SEC 1
J 0
(-2125 -1875);
DISPLAY 0.680851 (-2125 -1875);
PAINT MONO (-2125 -1875);
DISPLAY INVISIBLE (-2125 -1875);
FORCEPROP 0 LAST CDS_SEC 1
J 0
(-2125 -1875);
DISPLAY 1.021277 (-2125 -1875);
DISPLAY INVISIBLE (-2125 -1875);
FORCEADD Q_RES..2
(-1725 -2025);
FORCEPROP 1 LAST PART_NUMBER CS22002BB07
J 0
(-1675 -2125);
DISPLAY 0.723404 (-1675 -2125);
PAINT WHITE (-1675 -2125);
DISPLAY INVISIBLE (-1675 -2125);
FORCEPROP 1 LAST VALUE 2K
J 0
(-1670 -1925);
DISPLAY 0.723404 (-1670 -1925);
PAINT SKYBLUE (-1670 -1925);
FORCEPROP 1 LAST TOLERANCE 0.1%
J 0
(-1670 -1975);
DISPLAY 0.723404 (-1670 -1975);
PAINT SKYBLUE (-1670 -1975);
FORCEPROP 2 LAST ROOM HSC1_BOM1
J 0
(-1650 -1825);
DISPLAY 1.021277 (-1650 -1825);
FORCEPROP 1 LAST WATTAGE 1/16W
J 0
(-1675 -2025);
DISPLAY 0.723404 (-1675 -2025);
PAINT SKYBLUE (-1675 -2025);
FORCEPROP 1 LAST PACK_TYPE 0402LF
J 0
(-1675 -2175);
DISPLAY 0.723404 (-1675 -2175);
PAINT SKYBLUE (-1675 -2175);
FORCEPROP 1 LAST MATERIAL CHIP
J 0
(-1675 -2075);
DISPLAY 0.723404 (-1675 -2075);
PAINT SKYBLUE (-1675 -2075);
FORCEPROP 1 LAST LOCATION PR3915
J 0
(-1670 -1875);
DISPLAY 0.723404 (-1670 -1875);
PAINT AQUA (-1670 -1875);
FORCEPROP 1 LASTPIN (-1725 -1925) $PN 1
J 0
(-1720 -1963);
DISPLAY 0.787234 (-1720 -1963);
PAINT MONO (-1720 -1963);
FORCEPROP 1 LASTPIN (-1725 -2125) $PN 2
J 0
(-1720 -2115);
DISPLAY 0.787234 (-1720 -2115);
PAINT MONO (-1720 -2115);
FORCEPROP 2 LAST CDS_LIB pure_quanta
J 0
(-1725 -2025);
DISPLAY INVISIBLE (-1725 -2025);
FORCEPROP 1 LAST PATH I12
J 0
(-1675 -1850);
DISPLAY 0.978723 (-1675 -1850);
PAINT WHITE (-1675 -1850);
DISPLAY INVISIBLE (-1675 -1850);
FORCEPROP 0 LAST $SEC 1
J 0
(-1650 -1825);
DISPLAY 0.680851 (-1650 -1825);
PAINT MONO (-1650 -1825);
DISPLAY INVISIBLE (-1650 -1825);
FORCEPROP 0 LAST CDS_SEC 1
J 0
(-1650 -1825);
DISPLAY 1.021277 (-1650 -1825);
DISPLAY INVISIBLE (-1650 -1825);
FORCEADD Q_RES..2
(-1200 -2025);
FORCEPROP 1 LAST PART_NUMBER CS22002BB07
J 0
(-1150 -2125);
DISPLAY 0.723404 (-1150 -2125);
PAINT WHITE (-1150 -2125);
DISPLAY INVISIBLE (-1150 -2125);
FORCEPROP 1 LAST VALUE 2K
J 0
(-1145 -1925);
DISPLAY 0.723404 (-1145 -1925);
PAINT SKYBLUE (-1145 -1925);
FORCEPROP 1 LAST PACK_TYPE 0402LF
J 0
(-1150 -2175);
DISPLAY 0.723404 (-1150 -2175);
PAINT SKYBLUE (-1150 -2175);
FORCEPROP 1 LAST MATERIAL CHIP
J 0
(-1150 -2075);
DISPLAY 0.723404 (-1150 -2075);
PAINT SKYBLUE (-1150 -2075);
FORCEPROP 0 LAST ROOM HSC1_BOM1
J 0
(-1125 -1775);
DISPLAY 1.021277 (-1125 -1775);
FORCEPROP 1 LAST WATTAGE 1/16W
J 0
(-1150 -2025);
DISPLAY 0.723404 (-1150 -2025);
PAINT SKYBLUE (-1150 -2025);
FORCEPROP 1 LAST TOLERANCE 0.1%
J 0
(-1145 -1975);
DISPLAY 0.723404 (-1145 -1975);
PAINT SKYBLUE (-1145 -1975);
FORCEPROP 1 LAST $LOCATION PR1101
J 0
(-1145 -1875);
DISPLAY 0.723404 (-1145 -1875);
PAINT AQUA (-1145 -1875);
FORCEPROP 1 LASTPIN (-1200 -1925) $PN 1
J 0
(-1195 -1963);
DISPLAY 0.787234 (-1195 -1963);
PAINT MONO (-1195 -1963);
FORCEPROP 1 LASTPIN (-1200 -2125) $PN 2
J 0
(-1195 -2115);
DISPLAY 0.787234 (-1195 -2115);
PAINT MONO (-1195 -2115);
FORCEPROP 2 LAST CDS_LIB pure_quanta
J 0
(-1200 -2025);
DISPLAY INVISIBLE (-1200 -2025);
FORCEPROP 1 LAST PATH I13
J 0
(-1150 -1850);
DISPLAY 0.978723 (-1150 -1850);
PAINT WHITE (-1150 -1850);
DISPLAY INVISIBLE (-1150 -1850);
FORCEPROP 0 LAST CDS_LOCATION PR1101
J 0
(-1125 -1825);
DISPLAY 1.021277 (-1125 -1825);
DISPLAY INVISIBLE (-1125 -1825);
FORCEPROP 0 LAST $SEC 1
J 0
(-1125 -1825);
DISPLAY 0.680851 (-1125 -1825);
PAINT MONO (-1125 -1825);
DISPLAY INVISIBLE (-1125 -1825);
FORCEPROP 0 LAST CDS_SEC 1
J 0
(-1125 -1825);
DISPLAY 1.021277 (-1125 -1825);
DISPLAY INVISIBLE (-1125 -1825);
FORCEADD MP5991GLUZ..1
(-225 -1275);
FORCEPROP 1 LAST PART_NUMBER AL005991A00
J 0
(-545 -341);
DISPLAY 0.723404 (-545 -341);
PAINT GREEN (-545 -341);
DISPLAY INVISIBLE (-545 -341);
FORCEPROP 2 LAST VALUE MP5991GLU-Z
J 0
(-525 -150);
DISPLAY 1.021277 (-525 -150);
FORCEPROP 2 LAST PART_TYPE SMLF
J 0
(-525 -100);
DISPLAY 1.021277 (-525 -100);
FORCEPROP 1 LAST MATERIAL IC
J 0
(-545 -468);
DISPLAY 0.723404 (-545 -468);
PAINT GREEN (-545 -468);
FORCEPROP 2 LAST ROOM HSC1_BOM1
J 0
(-525 -50);
DISPLAY 1.021277 (-525 -50);
FORCEPROP 1 LAST LOCATION PU288
J 0
(-545 -194);
DISPLAY 0.723404 (-545 -194);
PAINT GREEN (-545 -194);
FORCEPROP 2 LASTPIN (-700 -1700) $PN 23
J 2
(-710 -1690);
DISPLAY 0.680851 (-710 -1690);
PAINT MONO (-710 -1690);
FORCEPROP 2 LASTPIN (250 -1350) $PN 3
J 0
(260 -1340);
DISPLAY 0.680851 (260 -1340);
PAINT MONO (260 -1340);
FORCEPROP 2 LASTPIN (250 -1450) $PN 6
J 0
(260 -1440);
DISPLAY 0.680851 (260 -1440);
PAINT MONO (260 -1440);
FORCEPROP 2 LASTPIN (-700 -2000) $PN 20
J 2
(-710 -1990);
DISPLAY 0.680851 (-710 -1990);
PAINT MONO (-710 -1990);
FORCEPROP 2 LASTPIN (250 -1650) $PN 5
J 0
(260 -1640);
DISPLAY 0.680851 (260 -1640);
PAINT MONO (260 -1640);
FORCEPROP 2 LASTPIN (-700 -1800) $PN 22
J 2
(-710 -1790);
DISPLAY 0.680851 (-710 -1790);
PAINT MONO (-710 -1790);
FORCEPROP 2 LASTPIN (-700 -1200) $PN 8
J 2
(-710 -1190);
DISPLAY 0.680851 (-710 -1190);
PAINT MONO (-710 -1190);
FORCEPROP 2 LASTPIN (250 -1550) $PN 7
J 0
(260 -1540);
DISPLAY 0.680851 (260 -1540);
PAINT MONO (260 -1540);
FORCEPROP 2 LASTPIN (-700 -1600) $PN 24
J 2
(-710 -1590);
DISPLAY 0.680851 (-710 -1590);
PAINT MONO (-710 -1590);
FORCEPROP 2 LASTPIN (-700 -1500) $PN 4
J 2
(-710 -1490);
DISPLAY 0.680851 (-710 -1490);
PAINT MONO (-710 -1490);
FORCEPROP 2 LASTPIN (-700 -1300) $PN 17
J 2
(-710 -1290);
DISPLAY 0.680851 (-710 -1290);
PAINT MONO (-710 -1290);
FORCEPROP 2 LASTPIN (250 -1850) $PN 19
J 0
(260 -1840);
DISPLAY 0.680851 (260 -1840);
PAINT MONO (260 -1840);
FORCEPROP 2 LASTPIN (-700 -1100) $PN 21
J 2
(-710 -1090);
DISPLAY 0.680851 (-710 -1090);
PAINT MONO (-710 -1090);
FORCEPROP 2 LASTPIN (-700 -550) $PN 9
J 2
(-710 -540);
DISPLAY 0.680851 (-710 -540);
PAINT MONO (-710 -540);
FORCEPROP 2 LASTPIN (-700 -600) $PN 10
J 2
(-710 -590);
DISPLAY 0.680851 (-710 -590);
PAINT MONO (-710 -590);
FORCEPROP 2 LASTPIN (-700 -650) $PN 11
J 2
(-710 -640);
DISPLAY 0.680851 (-710 -640);
PAINT MONO (-710 -640);
FORCEPROP 2 LASTPIN (-700 -700) $PN 12
J 2
(-710 -690);
DISPLAY 0.680851 (-710 -690);
PAINT MONO (-710 -690);
FORCEPROP 2 LASTPIN (-700 -750) $PN 13
J 2
(-710 -740);
DISPLAY 0.680851 (-710 -740);
PAINT MONO (-710 -740);
FORCEPROP 2 LASTPIN (-700 -800) $PN 14
J 2
(-710 -790);
DISPLAY 0.680851 (-710 -790);
PAINT MONO (-710 -790);
FORCEPROP 2 LASTPIN (-700 -850) $PN 15
J 2
(-710 -840);
DISPLAY 0.680851 (-710 -840);
PAINT MONO (-710 -840);
FORCEPROP 2 LASTPIN (-700 -900) $PN 16
J 2
(-710 -890);
DISPLAY 0.680851 (-710 -890);
PAINT MONO (-710 -890);
FORCEPROP 2 LASTPIN (-700 -950) $PN 33
J 2
(-710 -940);
DISPLAY 0.680851 (-710 -940);
PAINT MONO (-710 -940);
FORCEPROP 2 LASTPIN (250 -550) $PN 1
J 0
(260 -540);
DISPLAY 0.680851 (260 -540);
PAINT MONO (260 -540);
FORCEPROP 2 LASTPIN (250 -600) $PN 2
J 0
(260 -590);
DISPLAY 0.680851 (260 -590);
PAINT MONO (260 -590);
FORCEPROP 2 LASTPIN (250 -650) $PN 25
J 0
(260 -640);
DISPLAY 0.680851 (260 -640);
PAINT MONO (260 -640);
FORCEPROP 2 LASTPIN (250 -700) $PN 26
J 0
(260 -690);
DISPLAY 0.680851 (260 -690);
PAINT MONO (260 -690);
FORCEPROP 2 LASTPIN (250 -750) $PN 27
J 0
(260 -740);
DISPLAY 0.680851 (260 -740);
PAINT MONO (260 -740);
FORCEPROP 2 LASTPIN (250 -800) $PN 28
J 0
(260 -790);
DISPLAY 0.680851 (260 -790);
PAINT MONO (260 -790);
FORCEPROP 2 LASTPIN (250 -850) $PN 29
J 0
(260 -840);
DISPLAY 0.680851 (260 -840);
PAINT MONO (260 -840);
FORCEPROP 2 LASTPIN (250 -900) $PN 30
J 0
(260 -890);
DISPLAY 0.680851 (260 -890);
PAINT MONO (260 -890);
FORCEPROP 2 LASTPIN (250 -950) $PN 31
J 0
(260 -940);
DISPLAY 0.680851 (260 -940);
PAINT MONO (260 -940);
FORCEPROP 2 LASTPIN (250 -1000) $PN 32
J 0
(260 -990);
DISPLAY 0.680851 (260 -990);
PAINT MONO (260 -990);
FORCEPROP 2 LASTPIN (250 -1750) $PN 18
J 0
(260 -1740);
DISPLAY 0.680851 (260 -1740);
PAINT MONO (260 -1740);
FORCEPROP 1 LAST NEEDS_NO_SIZE TRUE
J 0
(-225 -1275);
DISPLAY 0.723404 (-225 -1275);
PAINT GREEN (-225 -1275);
DISPLAY INVISIBLE (-225 -1275);
FORCEPROP 1 LAST CDS_LMAN_SYM_OUTLINE -325,775,325,-775
J 0
(-225 -1275);
DISPLAY 0.468085 (-225 -1275);
PAINT GREEN (-225 -1275);
DISPLAY INVISIBLE (-225 -1275);
FORCEPROP 2 LAST CDS_LIB pure_quanta
J 0
(-225 -1275);
DISPLAY INVISIBLE (-225 -1275);
FORCEPROP 2 LAST SEC_TYPE 
J 0
(-525 -50);
DISPLAY 1.021277 (-525 -50);
DISPLAY INVISIBLE (-525 -50);
FORCEPROP 1 LAST PATH I14
J 0
(-225 -1275);
DISPLAY 0.723404 (-225 -1275);
PAINT GREEN (-225 -1275);
DISPLAY INVISIBLE (-225 -1275);
FORCEPROP 2 LAST SEC 1
J 0
(-525 -50);
DISPLAY 0.680851 (-525 -50);
PAINT MONO (-525 -50);
DISPLAY INVISIBLE (-525 -50);
FORCEADD Q_RES..1
(-2150 -1200);
FORCEPROP 1 LAST PART_NUMBER CS41202FB05
J 0
(-2000 -1175);
DISPLAY 0.723404 (-2000 -1175);
PAINT WHITE (-2000 -1175);
DISPLAY INVISIBLE (-2000 -1175);
FORCEPROP 1 LAST MATERIAL CHIP
J 0
(-2100 -1325);
DISPLAY 0.723404 (-2100 -1325);
PAINT SKYBLUE (-2100 -1325);
FORCEPROP 1 LAST WATTAGE 1/16W
J 2
(-2125 -1325);
DISPLAY 0.723404 (-2125 -1325);
PAINT SKYBLUE (-2125 -1325);
FORCEPROP 1 LAST VALUE 120K
J 2
(-2175 -1275);
DISPLAY 0.723404 (-2175 -1275);
PAINT SKYBLUE (-2175 -1275);
FORCEPROP 2 LAST ROOM HSC1_BOM1
J 0
(-2000 -1125);
DISPLAY 1.021277 (-2000 -1125);
FORCEPROP 1 LAST TOLERANCE 1%
J 0
(-2125 -1275);
DISPLAY 0.723404 (-2125 -1275);
PAINT SKYBLUE (-2125 -1275);
FORCEPROP 1 LAST PACK_TYPE 0402LF
J 0
(-2025 -1275);
DISPLAY 0.723404 (-2025 -1275);
PAINT SKYBLUE (-2025 -1275);
FORCEPROP 1 LAST LOCATION PR3912
J 0
(-2475 -1175);
DISPLAY 0.723404 (-2475 -1175);
PAINT AQUA (-2475 -1175);
FORCEPROP 1 LASTPIN (-2250 -1200) $PN 1
J 0
(-2238 -1188);
DISPLAY 0.787234 (-2238 -1188);
PAINT MONO (-2238 -1188);
FORCEPROP 1 LASTPIN (-2050 -1200) $PN 2
J 0
(-2088 -1188);
DISPLAY 0.787234 (-2088 -1188);
PAINT MONO (-2088 -1188);
FORCEPROP 2 LAST CDS_LIB pure_quanta
J 0
(-2150 -1200);
DISPLAY INVISIBLE (-2150 -1200);
FORCEPROP 1 LAST PATH I15
J 0
(-2200 -1050);
DISPLAY 0.978723 (-2200 -1050);
PAINT WHITE (-2200 -1050);
DISPLAY INVISIBLE (-2200 -1050);
FORCEPROP 0 LAST $SEC 1
J 0
(-2100 -1125);
DISPLAY 0.680851 (-2100 -1125);
PAINT MONO (-2100 -1125);
DISPLAY INVISIBLE (-2100 -1125);
FORCEPROP 0 LAST CDS_SEC 1
J 0
(-2100 -1125);
DISPLAY 1.021277 (-2100 -1125);
DISPLAY INVISIBLE (-2100 -1125);
FORCEADD OFFPAGE..5
(-1300 -1800);
FORCEPROP 2 LAST $XR2 301 
J 0
(-2065 -1800);
DISPLAY 0.638298 (-2065 -1800);
PAINT MONO (-2065 -1800);
FORCEPROP 2 LAST $XR1 303 
J 0
(-1945 -1800);
DISPLAY 0.638298 (-1945 -1800);
PAINT MONO (-1945 -1800);
FORCEPROP 2 LAST $XR0 302 
J 0
(-1825 -1800);
DISPLAY 0.638298 (-1825 -1800);
PAINT MONO (-1825 -1800);
FORCEPROP 2 LAST CDS_LIB standard
J 0
(-1300 -1800);
DISPLAY INVISIBLE (-1300 -1800);
FORCEPROP 1 LAST OFFPAGE TRUE
J 0
(-975 -1925);
DISPLAY 0.872340 (-975 -1925);
PAINT AQUA (-975 -1925);
DISPLAY INVISIBLE (-975 -1925);
FORCEPROP 1 LAST COMMENT_BODY TRUE
J 0
(-1200 -1875);
DISPLAY 1.170213 (-1200 -1875);
PAINT GREEN (-1200 -1875);
DISPLAY INVISIBLE (-1200 -1875);
FORCEPROP 2 LAST PATH I16
J 0
(-1550 -1725);
DISPLAY 1.021277 (-1550 -1725);
DISPLAY INVISIBLE (-1550 -1725);
FORCEADD Q_RES..1
(-1550 -1375);
FORCEPROP 1 LAST PART_NUMBER CS00002JB13
J 0
(-1875 -1425);
DISPLAY 0.723404 (-1875 -1425);
PAINT WHITE (-1875 -1425);
DISPLAY INVISIBLE (-1875 -1425);
FORCEPROP 1 LAST VALUE 0
J 2
(-1425 -1350);
DISPLAY 0.723404 (-1425 -1350);
PAINT SKYBLUE (-1425 -1350);
FORCEPROP 1 LAST WATTAGE 1/16W
J 2
(-1675 -1475);
DISPLAY 0.723404 (-1675 -1475);
PAINT SKYBLUE (-1675 -1475);
FORCEPROP 1 LAST MATERIAL CHIP
J 0
(-1375 -1475);
DISPLAY 0.723404 (-1375 -1475);
PAINT SKYBLUE (-1375 -1475);
FORCEPROP 1 LAST TOLERANCE 5%
J 0
(-1425 -1425);
DISPLAY 0.723404 (-1425 -1425);
PAINT SKYBLUE (-1425 -1425);
FORCEPROP 1 LAST PACK_TYPE 0402LF
J 0
(-1625 -1475);
DISPLAY 0.723404 (-1625 -1475);
PAINT SKYBLUE (-1625 -1475);
FORCEPROP 2 LAST ROOM HSC1_BOM1
J 0
(-1700 -1300);
DISPLAY 1.021277 (-1700 -1300);
FORCEPROP 1 LAST LOCATION PR3917
J 0
(-1850 -1375);
DISPLAY 0.723404 (-1850 -1375);
PAINT AQUA (-1850 -1375);
FORCEPROP 1 LASTPIN (-1650 -1375) $PN 1
J 0
(-1638 -1363);
DISPLAY 0.787234 (-1638 -1363);
PAINT MONO (-1638 -1363);
FORCEPROP 1 LASTPIN (-1450 -1375) $PN 2
J 0
(-1488 -1363);
DISPLAY 0.787234 (-1488 -1363);
PAINT MONO (-1488 -1363);
FORCEPROP 2 LAST CDS_LIB pure_quanta
J 0
(-1550 -1375);
DISPLAY INVISIBLE (-1550 -1375);
FORCEPROP 1 LAST PATH I17
J 0
(-1600 -1225);
DISPLAY 0.978723 (-1600 -1225);
PAINT WHITE (-1600 -1225);
DISPLAY INVISIBLE (-1600 -1225);
FORCEPROP 0 LAST $SEC 1
J 0
(-1425 -1300);
DISPLAY 0.680851 (-1425 -1300);
PAINT MONO (-1425 -1300);
DISPLAY INVISIBLE (-1425 -1300);
FORCEPROP 0 LAST CDS_SEC 1
J 0
(-1425 -1300);
DISPLAY 1.021277 (-1425 -1300);
DISPLAY INVISIBLE (-1425 -1300);
FORCEADD UNIVERSAL_POWER..1
(-1200 -400);
FORCEPROP 3 LASTPIN (-1200 -450) SIG_NAME P12V_PSU\g
J 0
(-1190 -440);
DISPLAY 0.659574 (-1190 -440);
PAINT MONO (-1190 -440);
DISPLAY INVISIBLE (-1190 -440);
FORCEPROP 1 LAST HDL_POWER P12V_PSU
J 1
(-1200 -350);
DISPLAY 0.723404 (-1200 -350);
PAINT GREEN (-1200 -350);
FORCEPROP 2 LAST BOM_COST MIO_VRD_SB
J 0
(-1200 -300);
DISPLAY 0.617021 (-1200 -300);
PAINT PURPLE (-1200 -300);
DISPLAY INVISIBLE (-1200 -300);
FORCEPROP 2 LAST CDS_LIB logical_power
J 0
(-1200 -400);
DISPLAY INVISIBLE (-1200 -400);
FORCEPROP 2 LAST ROOM AUX_SW
J 0
(-1200 -300);
DISPLAY 0.617021 (-1200 -300);
DISPLAY INVISIBLE (-1200 -300);
FORCEPROP 1 LAST PATH I18
J 0
(-1150 -375);
DISPLAY 0.872340 (-1150 -375);
PAINT AQUA (-1150 -375);
DISPLAY INVISIBLE (-1150 -375);
FORCEADD UNIVERSAL_GND..1
(-3675 1125);
FORCEPROP 3 LASTPIN (-3675 1175) SIG_NAME AGND_HSC\g
J 0
(-3665 1185);
DISPLAY 0.659574 (-3665 1185);
PAINT MONO (-3665 1185);
DISPLAY INVISIBLE (-3665 1185);
FORCEPROP 1 LAST HDL_POWER AGND_HSC
J 1
(-3650 1050);
DISPLAY 0.723404 (-3650 1050);
PAINT GREEN (-3650 1050);
FORCEPROP 2 LAST CDS_LIB logical_power
J 0
(-3675 1125);
DISPLAY INVISIBLE (-3675 1125);
FORCEPROP 1 LAST PATH I19
J 0
(-3600 1125);
DISPLAY 0.872340 (-3600 1125);
PAINT AQUA (-3600 1125);
DISPLAY INVISIBLE (-3600 1125);
FORCEADD Q_CAP..1
(-2875 -2025);
FORCEPROP 1 LAST PART_NUMBER TMP_QCH12206KB14
J 0
(-2800 -2125);
DISPLAY 0.723404 (-2800 -2125);
PAINT WHITE (-2800 -2125);
DISPLAY INVISIBLE (-2800 -2125);
FORCEPROP 1 LAST VALUE 220PF
J 0
(-2800 -1975);
DISPLAY 0.723404 (-2800 -1975);
PAINT SKYBLUE (-2800 -1975);
FORCEPROP 1 LAST MATERIAL EMPTY
J 0
(-2800 -2075);
DISPLAY 0.723404 (-2800 -2075);
PAINT RED (-2800 -2075);
FORCEPROP 1 LAST PACK_TYPE 0402
J 0
(-2800 -2175);
DISPLAY 0.723404 (-2800 -2175);
PAINT SKYBLUE (-2800 -2175);
FORCEPROP 1 LAST VOLTAGE 50V
J 0
(-2800 -2025);
DISPLAY 0.723404 (-2800 -2025);
PAINT SKYBLUE (-2800 -2025);
FORCEPROP 1 LAST LOCATION PC2183
J 0
(-2800 -1925);
DISPLAY 0.723404 (-2800 -1925);
PAINT AQUA (-2800 -1925);
FORCEPROP 1 LASTPIN (-2875 -1925) $PN 1
J 0
(-2865 -1945);
DISPLAY 0.787234 (-2865 -1945);
PAINT MONO (-2865 -1945);
FORCEPROP 1 LASTPIN (-2875 -2125) $PN 2
J 0
(-2865 -2145);
DISPLAY 0.787234 (-2865 -2145);
PAINT MONO (-2865 -2145);
FORCEPROP 2 LAST CDS_LIB pure_quanta
J 0
(-2875 -2025);
DISPLAY INVISIBLE (-2875 -2025);
FORCEPROP 1 LAST TOLERANCE 10%
J 0
(-2825 -2075);
DISPLAY 0.978723 (-2825 -2075);
PAINT SKYBLUE (-2825 -2075);
DISPLAY INVISIBLE (-2825 -2075);
FORCEPROP 1 LAST PATH I2
J 0
(-2825 -1875);
DISPLAY 0.978723 (-2825 -1875);
PAINT WHITE (-2825 -1875);
DISPLAY INVISIBLE (-2825 -1875);
FORCEPROP 0 LAST $SEC 1
J 0
(-2800 -1875);
DISPLAY 0.680851 (-2800 -1875);
PAINT MONO (-2800 -1875);
DISPLAY INVISIBLE (-2800 -1875);
FORCEPROP 0 LAST CDS_SEC 1
J 0
(-2800 -1875);
DISPLAY 1.021277 (-2800 -1875);
DISPLAY INVISIBLE (-2800 -1875);
FORCEADD Q_CAP..1
(-3675 1425);
FORCEPROP 1 LAST PART_NUMBER CH5104KEB02
J 0
(-3600 1375);
DISPLAY 0.723404 (-3600 1375);
PAINT WHITE (-3600 1375);
DISPLAY INVISIBLE (-3600 1375);
FORCEPROP 1 LAST MATERIAL X6S
J 0
(-3600 1425);
DISPLAY 0.723404 (-3600 1425);
PAINT SKYBLUE (-3600 1425);
FORCEPROP 1 LAST VOLTAGE 25V
J 0
(-3600 1475);
DISPLAY 0.723404 (-3600 1475);
PAINT SKYBLUE (-3600 1475);
FORCEPROP 1 LAST VALUE 1UF
J 0
(-3600 1525);
DISPLAY 0.723404 (-3600 1525);
PAINT SKYBLUE (-3600 1525);
FORCEPROP 2 LAST ROOM HSC1_BOM1
J 0
(-3600 1625);
DISPLAY 1.021277 (-3600 1625);
FORCEPROP 1 LAST PACK_TYPE C0402
J 0
(-3600 1325);
DISPLAY 0.723404 (-3600 1325);
PAINT SKYBLUE (-3600 1325);
FORCEPROP 1 LAST LOCATION PC1525
J 0
(-3600 1575);
DISPLAY 0.723404 (-3600 1575);
PAINT AQUA (-3600 1575);
FORCEPROP 1 LASTPIN (-3675 1525) $PN 1
J 0
(-3665 1505);
DISPLAY 0.787234 (-3665 1505);
PAINT MONO (-3665 1505);
FORCEPROP 1 LASTPIN (-3675 1325) $PN 2
J 0
(-3665 1305);
DISPLAY 0.787234 (-3665 1305);
PAINT MONO (-3665 1305);
FORCEPROP 2 LAST CDS_LIB pure_quanta
J 0
(-3675 1425);
DISPLAY INVISIBLE (-3675 1425);
FORCEPROP 1 LAST TOLERANCE 10%
J 0
(-3625 1375);
DISPLAY 0.978723 (-3625 1375);
PAINT SKYBLUE (-3625 1375);
DISPLAY INVISIBLE (-3625 1375);
FORCEPROP 1 LAST PATH I20
J 0
(-3625 1575);
DISPLAY 0.978723 (-3625 1575);
PAINT WHITE (-3625 1575);
DISPLAY INVISIBLE (-3625 1575);
FORCEPROP 0 LAST $SEC 1
J 0
(-3600 1625);
DISPLAY 0.680851 (-3600 1625);
PAINT MONO (-3600 1625);
DISPLAY INVISIBLE (-3600 1625);
FORCEPROP 0 LAST CDS_SEC 1
J 0
(-3600 1625);
DISPLAY 1.021277 (-3600 1625);
DISPLAY INVISIBLE (-3600 1625);
FORCEADD Q_RES..1
R 1
(-3675 1900);
FORCEPROP 1 LAST PART_NUMBER CS00002JB13
J 0
(-3600 1800);
DISPLAY 0.723404 (-3600 1800);
PAINT WHITE (-3600 1800);
DISPLAY INVISIBLE (-3600 1800);
FORCEPROP 1 LAST WATTAGE 1/16W
J 0
(-3600 1850);
DISPLAY 0.723404 (-3600 1850);
PAINT SKYBLUE (-3600 1850);
FORCEPROP 1 LAST PACK_TYPE 0402LF
J 0
(-3600 1750);
DISPLAY 0.723404 (-3600 1750);
PAINT SKYBLUE (-3600 1750);
FORCEPROP 1 LAST VALUE 0
R 2
J 0
(-3575 2025);
DISPLAY 0.723404 (-3575 2025);
PAINT SKYBLUE (-3575 2025);
FORCEPROP 2 LAST ROOM HSC1_BOM1
J 0
(-3600 2100);
DISPLAY 1.021277 (-3600 2100);
FORCEPROP 1 LAST TOLERANCE 5%
J 0
(-3600 1950);
DISPLAY 0.723404 (-3600 1950);
PAINT SKYBLUE (-3600 1950);
FORCEPROP 1 LAST MATERIAL CHIP
J 0
(-3600 1900);
DISPLAY 0.787234 (-3600 1900);
PAINT SKYBLUE (-3600 1900);
FORCEPROP 1 LAST LOCATION PR3910
J 0
(-3600 2050);
DISPLAY 0.723404 (-3600 2050);
PAINT AQUA (-3600 2050);
FORCEPROP 1 LASTPIN (-3675 1800) $PN 1
R 1
J 0
(-3687 1812);
DISPLAY 0.787234 (-3687 1812);
PAINT MONO (-3687 1812);
FORCEPROP 1 LASTPIN (-3675 2000) $PN 2
R 1
J 0
(-3687 1962);
DISPLAY 0.787234 (-3687 1962);
PAINT MONO (-3687 1962);
FORCEPROP 2 LAST CDS_LIB pure_quanta
J 0
(-3675 1900);
DISPLAY INVISIBLE (-3675 1900);
FORCEPROP 1 LAST PATH I21
R 1
J 0
(-3825 1850);
DISPLAY 0.978723 (-3825 1850);
PAINT WHITE (-3825 1850);
DISPLAY INVISIBLE (-3825 1850);
FORCEPROP 0 LAST $SEC 1
R 1
J 0
(-3600 2100);
DISPLAY 0.680851 (-3600 2100);
PAINT MONO (-3600 2100);
DISPLAY INVISIBLE (-3600 2100);
FORCEPROP 0 LAST CDS_SEC 1
R 1
J 0
(-3600 2100);
DISPLAY 1.021277 (-3600 2100);
DISPLAY INVISIBLE (-3600 2100);
FORCEADD UNIVERSAL_GND..1
(-2900 475);
FORCEPROP 3 LASTPIN (-2900 525) SIG_NAME AGND_HSC\g
J 0
(-2890 535);
DISPLAY 0.659574 (-2890 535);
PAINT MONO (-2890 535);
DISPLAY INVISIBLE (-2890 535);
FORCEPROP 1 LAST HDL_POWER AGND_HSC
J 1
(-2875 400);
DISPLAY 0.723404 (-2875 400);
PAINT GREEN (-2875 400);
FORCEPROP 2 LAST CDS_LIB logical_power
J 0
(-2900 475);
DISPLAY INVISIBLE (-2900 475);
FORCEPROP 1 LAST PATH I22
J 0
(-2825 475);
DISPLAY 0.872340 (-2825 475);
PAINT AQUA (-2825 475);
DISPLAY INVISIBLE (-2825 475);
FORCEADD Q_CAP..1
(-2900 775);
FORCEPROP 1 LAST PART_NUMBER TMP_QCH12206KB14
J 0
(-2825 675);
DISPLAY 0.723404 (-2825 675);
PAINT WHITE (-2825 675);
DISPLAY INVISIBLE (-2825 675);
FORCEPROP 1 LAST MATERIAL X7R
J 0
(-2825 725);
DISPLAY 0.723404 (-2825 725);
PAINT SKYBLUE (-2825 725);
FORCEPROP 1 LAST PACK_TYPE 0402
J 0
(-2825 625);
DISPLAY 0.723404 (-2825 625);
PAINT SKYBLUE (-2825 625);
FORCEPROP 1 LAST VALUE 220PF
J 0
(-2825 825);
DISPLAY 0.723404 (-2825 825);
PAINT SKYBLUE (-2825 825);
FORCEPROP 2 LAST ROOM HSC1_BOM1
J 0
(-2825 925);
DISPLAY 1.021277 (-2825 925);
FORCEPROP 1 LAST VOLTAGE 50V
J 0
(-2825 775);
DISPLAY 0.723404 (-2825 775);
PAINT SKYBLUE (-2825 775);
FORCEPROP 1 LAST LOCATION PC2182
J 0
(-2825 875);
DISPLAY 0.723404 (-2825 875);
PAINT AQUA (-2825 875);
FORCEPROP 1 LASTPIN (-2900 875) $PN 1
J 0
(-2890 855);
DISPLAY 0.787234 (-2890 855);
PAINT MONO (-2890 855);
FORCEPROP 1 LASTPIN (-2900 675) $PN 2
J 0
(-2890 655);
DISPLAY 0.787234 (-2890 655);
PAINT MONO (-2890 655);
FORCEPROP 1 LAST TOLERANCE 10%
J 0
(-2850 725);
DISPLAY 0.978723 (-2850 725);
PAINT SKYBLUE (-2850 725);
DISPLAY INVISIBLE (-2850 725);
FORCEPROP 2 LAST CDS_LIB pure_quanta
J 0
(-2900 775);
DISPLAY INVISIBLE (-2900 775);
FORCEPROP 1 LAST PATH I23
J 0
(-2850 925);
DISPLAY 0.978723 (-2850 925);
PAINT WHITE (-2850 925);
DISPLAY INVISIBLE (-2850 925);
FORCEPROP 0 LAST $SEC 1
J 0
(-2825 925);
DISPLAY 0.680851 (-2825 925);
PAINT MONO (-2825 925);
DISPLAY INVISIBLE (-2825 925);
FORCEPROP 0 LAST CDS_SEC 1
J 0
(-2825 925);
DISPLAY 1.021277 (-2825 925);
DISPLAY INVISIBLE (-2825 925);
FORCEADD OFFPAGE..4
R 2
(-3000 1300);
FORCEPROP 2 LAST $XR2 303 
J 0
(-3282 1264);
DISPLAY 0.638298 (-3282 1264);
PAINT MONO (-3282 1264);
FORCEPROP 2 LAST $XR1 302 
J 0
(-3402 1300);
DISPLAY 0.638298 (-3402 1300);
PAINT MONO (-3402 1300);
FORCEPROP 2 LAST $XR0 301 
J 0
(-3282 1300);
DISPLAY 0.638298 (-3282 1300);
PAINT MONO (-3282 1300);
FORCEPROP 2 LAST CDS_LIB standard
J 0
(-3000 1300);
DISPLAY INVISIBLE (-3000 1300);
FORCEPROP 1 LAST OFFPAGE TRUE
J 2
(-3325 1175);
DISPLAY 0.872340 (-3325 1175);
PAINT GREEN (-3325 1175);
DISPLAY INVISIBLE (-3325 1175);
FORCEPROP 1 LAST COMMENT_BODY TRUE
J 2
(-2975 1200);
DISPLAY 0.872340 (-2975 1200);
PAINT GREEN (-2975 1200);
DISPLAY INVISIBLE (-2975 1200);
FORCEPROP 2 LAST PATH I24
J 0
(-3275 1350);
DISPLAY 1.021277 (-3275 1350);
DISPLAY INVISIBLE (-3275 1350);
FORCEADD UNIVERSAL_GND..1
(-2850 1525);
FORCEPROP 3 LASTPIN (-2850 1575) SIG_NAME AGND_HSC\g
J 0
(-2840 1585);
DISPLAY 0.659574 (-2840 1585);
PAINT MONO (-2840 1585);
DISPLAY INVISIBLE (-2840 1585);
FORCEPROP 1 LAST HDL_POWER AGND_HSC
J 1
(-2825 1450);
DISPLAY 0.723404 (-2825 1450);
PAINT GREEN (-2825 1450);
FORCEPROP 2 LAST CDS_LIB logical_power
J 0
(-2850 1525);
DISPLAY INVISIBLE (-2850 1525);
FORCEPROP 1 LAST PATH I25
J 0
(-2775 1525);
DISPLAY 0.872340 (-2775 1525);
PAINT AQUA (-2775 1525);
DISPLAY INVISIBLE (-2775 1525);
FORCEADD OFFPAGE..4
R 2
(-2375 1200);
FORCEPROP 2 LAST $XR2 303 
J 0
(-2867 1200);
DISPLAY 0.638298 (-2867 1200);
PAINT MONO (-2867 1200);
FORCEPROP 2 LAST $XR1 302 
J 0
(-2747 1200);
DISPLAY 0.638298 (-2747 1200);
PAINT MONO (-2747 1200);
FORCEPROP 2 LAST $XR0 301 
J 0
(-2627 1200);
DISPLAY 0.638298 (-2627 1200);
PAINT MONO (-2627 1200);
FORCEPROP 2 LAST CDS_LIB standard
J 0
(-2375 1200);
DISPLAY INVISIBLE (-2375 1200);
FORCEPROP 1 LAST OFFPAGE TRUE
J 2
(-2700 1075);
DISPLAY 0.872340 (-2700 1075);
PAINT GREEN (-2700 1075);
DISPLAY INVISIBLE (-2700 1075);
FORCEPROP 1 LAST COMMENT_BODY TRUE
J 2
(-2350 1100);
DISPLAY 0.872340 (-2350 1100);
PAINT GREEN (-2350 1100);
DISPLAY INVISIBLE (-2350 1100);
FORCEPROP 2 LAST PATH I26
J 0
(-2625 1250);
DISPLAY 1.021277 (-2625 1250);
DISPLAY INVISIBLE (-2625 1250);
FORCEADD OFFPAGE..4
R 2
(-2275 1425);
FORCEPROP 2 LAST $XR2 303 
J 0
(-2767 1425);
DISPLAY 0.638298 (-2767 1425);
PAINT MONO (-2767 1425);
FORCEPROP 2 LAST $XR0 301 
J 0
(-2527 1425);
DISPLAY 0.638298 (-2527 1425);
PAINT MONO (-2527 1425);
FORCEPROP 2 LAST $XR1 302 
J 0
(-2647 1425);
DISPLAY 0.638298 (-2647 1425);
PAINT MONO (-2647 1425);
FORCEPROP 2 LAST CDS_LIB standard
J 0
(-2275 1425);
DISPLAY INVISIBLE (-2275 1425);
FORCEPROP 1 LAST OFFPAGE TRUE
J 2
(-2600 1300);
DISPLAY 0.872340 (-2600 1300);
PAINT GREEN (-2600 1300);
DISPLAY INVISIBLE (-2600 1300);
FORCEPROP 1 LAST COMMENT_BODY TRUE
J 2
(-2250 1325);
DISPLAY 0.872340 (-2250 1325);
PAINT GREEN (-2250 1325);
DISPLAY INVISIBLE (-2250 1325);
FORCEPROP 2 LAST PATH I27
J 0
(-2525 1475);
DISPLAY 1.021277 (-2525 1475);
DISPLAY INVISIBLE (-2525 1475);
FORCEADD UNIVERSAL_POWER..1
(-3675 2150);
FORCEPROP 3 LASTPIN (-3675 2100) SIG_NAME HSC_VDD\g
J 0
(-3665 2110);
DISPLAY 0.659574 (-3665 2110);
PAINT MONO (-3665 2110);
DISPLAY INVISIBLE (-3665 2110);
FORCEPROP 1 LAST HDL_POWER HSC_VDD
J 1
(-3675 2200);
DISPLAY 0.723404 (-3675 2200);
PAINT GREEN (-3675 2200);
FORCEPROP 2 LAST CDS_LIB logical_power
J 0
(-3675 2150);
DISPLAY INVISIBLE (-3675 2150);
FORCEPROP 2 LAST BOM_COST MIO_VRD_SB
J 0
(-3675 2250);
DISPLAY 0.617021 (-3675 2250);
PAINT PURPLE (-3675 2250);
DISPLAY INVISIBLE (-3675 2250);
FORCEPROP 2 LAST ROOM AUX_SW
J 0
(-3675 2250);
DISPLAY 0.617021 (-3675 2250);
DISPLAY INVISIBLE (-3675 2250);
FORCEPROP 1 LAST PATH I28
J 0
(-3625 2175);
DISPLAY 0.872340 (-3625 2175);
PAINT AQUA (-3625 2175);
DISPLAY INVISIBLE (-3625 2175);
FORCEADD Q_CAP..1
(-2225 775);
FORCEPROP 1 LAST PART_NUMBER CH21006KB16
J 0
(-2150 675);
DISPLAY 0.723404 (-2150 675);
PAINT WHITE (-2150 675);
DISPLAY INVISIBLE (-2150 675);
FORCEPROP 1 LAST VOLTAGE 50V
J 0
(-2150 775);
DISPLAY 0.723404 (-2150 775);
PAINT SKYBLUE (-2150 775);
FORCEPROP 1 LAST MATERIAL EMPTY
J 0
(-2150 725);
DISPLAY 0.723404 (-2150 725);
PAINT RED (-2150 725);
FORCEPROP 1 LAST VALUE 1NF
J 0
(-2150 825);
DISPLAY 0.723404 (-2150 825);
PAINT SKYBLUE (-2150 825);
FORCEPROP 1 LAST PACK_TYPE 0402
J 0
(-2150 625);
DISPLAY 0.723404 (-2150 625);
PAINT SKYBLUE (-2150 625);
FORCEPROP 1 LAST LOCATION PC2347
J 0
(-2150 875);
DISPLAY 0.723404 (-2150 875);
PAINT AQUA (-2150 875);
FORCEPROP 1 LASTPIN (-2225 875) $PN 1
J 0
(-2215 855);
DISPLAY 0.787234 (-2215 855);
PAINT MONO (-2215 855);
FORCEPROP 1 LASTPIN (-2225 675) $PN 2
J 0
(-2215 655);
DISPLAY 0.787234 (-2215 655);
PAINT MONO (-2215 655);
FORCEPROP 1 LAST TOLERANCE 10%
J 0
(-2175 725);
DISPLAY 0.978723 (-2175 725);
PAINT SKYBLUE (-2175 725);
DISPLAY INVISIBLE (-2175 725);
FORCEPROP 2 LAST CDS_LIB pure_quanta
J 0
(-2225 775);
DISPLAY INVISIBLE (-2225 775);
FORCEPROP 1 LAST PATH I29
J 0
(-2175 925);
DISPLAY 0.978723 (-2175 925);
PAINT WHITE (-2175 925);
DISPLAY INVISIBLE (-2175 925);
FORCEPROP 0 LAST $SEC 1
J 0
(-2150 925);
DISPLAY 0.680851 (-2150 925);
PAINT MONO (-2150 925);
DISPLAY INVISIBLE (-2150 925);
FORCEPROP 0 LAST CDS_SEC 1
J 0
(-2150 925);
DISPLAY 1.021277 (-2150 925);
DISPLAY INVISIBLE (-2150 925);
FORCEADD UNIVERSAL_GND..1
(-3700 -1675);
FORCEPROP 3 LASTPIN (-3700 -1625) SIG_NAME AGND_HSC\g
J 0
(-3690 -1615);
DISPLAY 0.659574 (-3690 -1615);
PAINT MONO (-3690 -1615);
DISPLAY INVISIBLE (-3690 -1615);
FORCEPROP 1 LAST HDL_POWER AGND_HSC
J 1
(-3675 -1750);
DISPLAY 0.723404 (-3675 -1750);
PAINT GREEN (-3675 -1750);
FORCEPROP 2 LAST CDS_LIB logical_power
J 0
(-3700 -1675);
DISPLAY INVISIBLE (-3700 -1675);
FORCEPROP 1 LAST PATH I3
J 0
(-3625 -1675);
DISPLAY 0.872340 (-3625 -1675);
PAINT AQUA (-3625 -1675);
DISPLAY INVISIBLE (-3625 -1675);
FORCEADD Q_RES..2
(-1725 775);
FORCEPROP 1 LAST PART_NUMBER CS22002BB07
J 0
(-1675 675);
DISPLAY 0.723404 (-1675 675);
PAINT WHITE (-1675 675);
DISPLAY INVISIBLE (-1675 675);
FORCEPROP 2 LAST ROOM HSC1_BOM1
J 0
(-1650 975);
DISPLAY 1.021277 (-1650 975);
FORCEPROP 1 LAST VALUE 2K
J 0
(-1670 875);
DISPLAY 0.723404 (-1670 875);
PAINT SKYBLUE (-1670 875);
FORCEPROP 1 LAST TOLERANCE 0.1%
J 0
(-1670 825);
DISPLAY 0.723404 (-1670 825);
PAINT SKYBLUE (-1670 825);
FORCEPROP 1 LAST WATTAGE 1/16W
J 0
(-1675 775);
DISPLAY 0.723404 (-1675 775);
PAINT SKYBLUE (-1675 775);
FORCEPROP 1 LAST MATERIAL CHIP
J 0
(-1675 725);
DISPLAY 0.723404 (-1675 725);
PAINT SKYBLUE (-1675 725);
FORCEPROP 1 LAST PACK_TYPE 0402LF
J 0
(-1675 625);
DISPLAY 0.723404 (-1675 625);
PAINT SKYBLUE (-1675 625);
FORCEPROP 1 LAST LOCATION PR3914
J 0
(-1670 925);
DISPLAY 0.723404 (-1670 925);
PAINT AQUA (-1670 925);
FORCEPROP 1 LASTPIN (-1725 875) $PN 1
J 0
(-1720 837);
DISPLAY 0.787234 (-1720 837);
PAINT MONO (-1720 837);
FORCEPROP 1 LASTPIN (-1725 675) $PN 2
J 0
(-1720 685);
DISPLAY 0.787234 (-1720 685);
PAINT MONO (-1720 685);
FORCEPROP 2 LAST CDS_LIB pure_quanta
J 0
(-1725 775);
DISPLAY INVISIBLE (-1725 775);
FORCEPROP 1 LAST PATH I30
J 0
(-1675 950);
DISPLAY 0.978723 (-1675 950);
PAINT WHITE (-1675 950);
DISPLAY INVISIBLE (-1675 950);
FORCEPROP 0 LAST $SEC 1
J 0
(-1650 975);
DISPLAY 0.680851 (-1650 975);
PAINT MONO (-1650 975);
DISPLAY INVISIBLE (-1650 975);
FORCEPROP 0 LAST CDS_SEC 1
J 0
(-1650 975);
DISPLAY 1.021277 (-1650 975);
DISPLAY INVISIBLE (-1650 975);
FORCEADD OFFPAGE..5
(-1300 1000);
FORCEPROP 2 LAST $XR2 301 
J 0
(-2065 1000);
DISPLAY 0.638298 (-2065 1000);
PAINT MONO (-2065 1000);
FORCEPROP 2 LAST $XR1 303 
J 0
(-1945 1000);
DISPLAY 0.638298 (-1945 1000);
PAINT MONO (-1945 1000);
FORCEPROP 2 LAST $XR0 302 
J 0
(-1825 1000);
DISPLAY 0.638298 (-1825 1000);
PAINT MONO (-1825 1000);
FORCEPROP 2 LAST CDS_LIB standard
J 0
(-1300 1000);
DISPLAY INVISIBLE (-1300 1000);
FORCEPROP 1 LAST OFFPAGE TRUE
J 0
(-975 875);
DISPLAY 0.872340 (-975 875);
PAINT AQUA (-975 875);
DISPLAY INVISIBLE (-975 875);
FORCEPROP 1 LAST COMMENT_BODY TRUE
J 0
(-1200 925);
DISPLAY 1.170213 (-1200 925);
PAINT GREEN (-1200 925);
DISPLAY INVISIBLE (-1200 925);
FORCEPROP 2 LAST PATH I31
J 0
(-1550 1075);
DISPLAY 1.021277 (-1550 1075);
DISPLAY INVISIBLE (-1550 1075);
FORCEADD Q_RES..1
(-2150 1600);
FORCEPROP 1 LAST PART_NUMBER CS41202FB05
J 0
(-2000 1625);
DISPLAY 0.723404 (-2000 1625);
PAINT WHITE (-2000 1625);
DISPLAY INVISIBLE (-2000 1625);
FORCEPROP 1 LAST MATERIAL CHIP
J 0
(-2100 1475);
DISPLAY 0.723404 (-2100 1475);
PAINT SKYBLUE (-2100 1475);
FORCEPROP 1 LAST WATTAGE 1/16W
J 2
(-2125 1475);
DISPLAY 0.723404 (-2125 1475);
PAINT SKYBLUE (-2125 1475);
FORCEPROP 1 LAST TOLERANCE 1%
J 0
(-2125 1525);
DISPLAY 0.723404 (-2125 1525);
PAINT SKYBLUE (-2125 1525);
FORCEPROP 1 LAST VALUE 120K
J 2
(-2175 1525);
DISPLAY 0.723404 (-2175 1525);
PAINT SKYBLUE (-2175 1525);
FORCEPROP 0 LAST ROOM HSC1_BOM1
J 0
(-2275 1725);
DISPLAY 1.021277 (-2275 1725);
FORCEPROP 1 LAST PACK_TYPE 0402LF
J 0
(-2025 1525);
DISPLAY 0.723404 (-2025 1525);
PAINT SKYBLUE (-2025 1525);
FORCEPROP 1 LAST $LOCATION PR1134
J 0
(-2425 1625);
DISPLAY 0.723404 (-2425 1625);
PAINT AQUA (-2425 1625);
FORCEPROP 1 LASTPIN (-2250 1600) $PN 1
J 0
(-2238 1612);
DISPLAY 0.787234 (-2238 1612);
PAINT MONO (-2238 1612);
FORCEPROP 1 LASTPIN (-2050 1600) $PN 2
J 0
(-2088 1612);
DISPLAY 0.787234 (-2088 1612);
PAINT MONO (-2088 1612);
FORCEPROP 2 LAST CDS_LIB pure_quanta
J 0
(-2150 1600);
DISPLAY INVISIBLE (-2150 1600);
FORCEPROP 1 LAST PATH I32
J 0
(-2200 1750);
DISPLAY 0.978723 (-2200 1750);
PAINT WHITE (-2200 1750);
DISPLAY INVISIBLE (-2200 1750);
FORCEPROP 0 LAST CDS_LOCATION PR1134
J 0
(-2100 1675);
DISPLAY 1.021277 (-2100 1675);
DISPLAY INVISIBLE (-2100 1675);
FORCEPROP 0 LAST $SEC 1
J 0
(-2100 1675);
DISPLAY 0.680851 (-2100 1675);
PAINT MONO (-2100 1675);
DISPLAY INVISIBLE (-2100 1675);
FORCEPROP 0 LAST CDS_SEC 1
J 0
(-2100 1675);
DISPLAY 1.021277 (-2100 1675);
DISPLAY INVISIBLE (-2100 1675);
FORCEADD Q_RES..1
(-1575 1425);
FORCEPROP 1 LAST PART_NUMBER CS00002JB13
J 0
(-1900 1375);
DISPLAY 0.723404 (-1900 1375);
PAINT WHITE (-1900 1375);
DISPLAY INVISIBLE (-1900 1375);
FORCEPROP 1 LAST VALUE 0
J 2
(-1425 1450);
DISPLAY 0.723404 (-1425 1450);
PAINT SKYBLUE (-1425 1450);
FORCEPROP 2 LAST ROOM HSC1_BOM1
J 0
(-1750 1500);
DISPLAY 1.021277 (-1750 1500);
FORCEPROP 1 LAST MATERIAL CHIP
J 0
(-1400 1325);
DISPLAY 0.723404 (-1400 1325);
PAINT SKYBLUE (-1400 1325);
FORCEPROP 1 LAST PACK_TYPE 0402LF
J 0
(-1650 1325);
DISPLAY 0.723404 (-1650 1325);
PAINT SKYBLUE (-1650 1325);
FORCEPROP 1 LAST WATTAGE 1/16W
J 2
(-1700 1325);
DISPLAY 0.723404 (-1700 1325);
PAINT SKYBLUE (-1700 1325);
FORCEPROP 1 LAST TOLERANCE 5%
J 0
(-1450 1375);
DISPLAY 0.723404 (-1450 1375);
PAINT SKYBLUE (-1450 1375);
FORCEPROP 1 LAST LOCATION PR3916
J 0
(-1875 1425);
DISPLAY 0.723404 (-1875 1425);
PAINT AQUA (-1875 1425);
FORCEPROP 1 LASTPIN (-1675 1425) $PN 1
J 0
(-1663 1437);
DISPLAY 0.787234 (-1663 1437);
PAINT MONO (-1663 1437);
FORCEPROP 1 LASTPIN (-1475 1425) $PN 2
J 0
(-1513 1437);
DISPLAY 0.787234 (-1513 1437);
PAINT MONO (-1513 1437);
FORCEPROP 2 LAST CDS_LIB pure_quanta
J 0
(-1575 1425);
DISPLAY INVISIBLE (-1575 1425);
FORCEPROP 1 LAST PATH I33
J 0
(-1625 1575);
DISPLAY 0.978723 (-1625 1575);
PAINT WHITE (-1625 1575);
DISPLAY INVISIBLE (-1625 1575);
FORCEPROP 0 LAST $SEC 1
J 0
(-1450 1500);
DISPLAY 0.680851 (-1450 1500);
PAINT MONO (-1450 1500);
DISPLAY INVISIBLE (-1450 1500);
FORCEPROP 0 LAST CDS_SEC 1
J 0
(-1450 1500);
DISPLAY 1.021277 (-1450 1500);
DISPLAY INVISIBLE (-1450 1500);
FORCEADD Q_RES..2
(-1200 775);
FORCEPROP 1 LAST PART_NUMBER CS22002BB07
J 0
(-1150 675);
DISPLAY 0.723404 (-1150 675);
PAINT WHITE (-1150 675);
DISPLAY INVISIBLE (-1150 675);
FORCEPROP 1 LAST VALUE 2K
J 0
(-1145 875);
DISPLAY 0.723404 (-1145 875);
PAINT SKYBLUE (-1145 875);
FORCEPROP 1 LAST TOLERANCE 0.1%
J 0
(-1145 825);
DISPLAY 0.723404 (-1145 825);
PAINT SKYBLUE (-1145 825);
FORCEPROP 1 LAST MATERIAL CHIP
J 0
(-1150 725);
DISPLAY 0.723404 (-1150 725);
PAINT SKYBLUE (-1150 725);
FORCEPROP 1 LAST WATTAGE 1/16W
J 0
(-1150 775);
DISPLAY 0.723404 (-1150 775);
PAINT SKYBLUE (-1150 775);
FORCEPROP 2 LAST ROOM HSC1_BOM1
J 0
(-1125 975);
DISPLAY 1.021277 (-1125 975);
FORCEPROP 1 LAST PACK_TYPE 0402LF
J 0
(-1150 625);
DISPLAY 0.723404 (-1150 625);
PAINT SKYBLUE (-1150 625);
FORCEPROP 1 LAST LOCATION PR3918
J 0
(-1145 925);
DISPLAY 0.723404 (-1145 925);
PAINT AQUA (-1145 925);
FORCEPROP 1 LASTPIN (-1200 875) $PN 1
J 0
(-1195 837);
DISPLAY 0.787234 (-1195 837);
PAINT MONO (-1195 837);
FORCEPROP 1 LASTPIN (-1200 675) $PN 2
J 0
(-1195 685);
DISPLAY 0.787234 (-1195 685);
PAINT MONO (-1195 685);
FORCEPROP 2 LAST CDS_LIB pure_quanta
J 0
(-1200 775);
DISPLAY INVISIBLE (-1200 775);
FORCEPROP 1 LAST PATH I34
J 0
(-1150 950);
DISPLAY 0.978723 (-1150 950);
PAINT WHITE (-1150 950);
DISPLAY INVISIBLE (-1150 950);
FORCEPROP 0 LAST $SEC 1
J 0
(-1125 975);
DISPLAY 0.680851 (-1125 975);
PAINT MONO (-1125 975);
DISPLAY INVISIBLE (-1125 975);
FORCEPROP 0 LAST CDS_SEC 1
J 0
(-1125 975);
DISPLAY 1.021277 (-1125 975);
DISPLAY INVISIBLE (-1125 975);
FORCEADD MP5991GLUZ..1
(-225 1525);
FORCEPROP 1 LAST PART_NUMBER AL005991A00
J 0
(-545 2459);
DISPLAY 0.723404 (-545 2459);
PAINT GREEN (-545 2459);
DISPLAY INVISIBLE (-545 2459);
FORCEPROP 1 LAST MATERIAL IC
J 0
(-545 2332);
DISPLAY 0.723404 (-545 2332);
PAINT GREEN (-545 2332);
FORCEPROP 2 LAST VALUE MP5991GLU-Z
J 0
(-525 2650);
DISPLAY 1.021277 (-525 2650);
FORCEPROP 2 LAST PART_TYPE SMLF
J 0
(-525 2700);
DISPLAY 1.021277 (-525 2700);
FORCEPROP 2 LAST ROOM HSC1_BOM1
J 0
(-525 2750);
DISPLAY 1.021277 (-525 2750);
FORCEPROP 1 LAST LOCATION PU287
J 0
(-545 2606);
DISPLAY 0.723404 (-545 2606);
PAINT GREEN (-545 2606);
FORCEPROP 2 LASTPIN (-700 1100) $PN 23
J 2
(-710 1110);
DISPLAY 0.680851 (-710 1110);
PAINT MONO (-710 1110);
FORCEPROP 2 LASTPIN (250 1450) $PN 3
J 0
(260 1460);
DISPLAY 0.680851 (260 1460);
PAINT MONO (260 1460);
FORCEPROP 2 LASTPIN (250 1350) $PN 6
J 0
(260 1360);
DISPLAY 0.680851 (260 1360);
PAINT MONO (260 1360);
FORCEPROP 2 LASTPIN (-700 800) $PN 20
J 2
(-710 810);
DISPLAY 0.680851 (-710 810);
PAINT MONO (-710 810);
FORCEPROP 2 LASTPIN (250 1150) $PN 5
J 0
(260 1160);
DISPLAY 0.680851 (260 1160);
PAINT MONO (260 1160);
FORCEPROP 2 LASTPIN (-700 1000) $PN 22
J 2
(-710 1010);
DISPLAY 0.680851 (-710 1010);
PAINT MONO (-710 1010);
FORCEPROP 2 LASTPIN (-700 1600) $PN 8
J 2
(-710 1610);
DISPLAY 0.680851 (-710 1610);
PAINT MONO (-710 1610);
FORCEPROP 2 LASTPIN (250 1250) $PN 7
J 0
(260 1260);
DISPLAY 0.680851 (260 1260);
PAINT MONO (260 1260);
FORCEPROP 2 LASTPIN (-700 1200) $PN 24
J 2
(-710 1210);
DISPLAY 0.680851 (-710 1210);
PAINT MONO (-710 1210);
FORCEPROP 2 LASTPIN (-700 1300) $PN 4
J 2
(-710 1310);
DISPLAY 0.680851 (-710 1310);
PAINT MONO (-710 1310);
FORCEPROP 2 LASTPIN (-700 1500) $PN 17
J 2
(-710 1510);
DISPLAY 0.680851 (-710 1510);
PAINT MONO (-710 1510);
FORCEPROP 2 LASTPIN (250 950) $PN 19
J 0
(260 960);
DISPLAY 0.680851 (260 960);
PAINT MONO (260 960);
FORCEPROP 2 LASTPIN (-700 1700) $PN 21
J 2
(-710 1710);
DISPLAY 0.680851 (-710 1710);
PAINT MONO (-710 1710);
FORCEPROP 2 LASTPIN (-700 2250) $PN 9
J 2
(-710 2260);
DISPLAY 0.680851 (-710 2260);
PAINT MONO (-710 2260);
FORCEPROP 2 LASTPIN (-700 2200) $PN 10
J 2
(-710 2210);
DISPLAY 0.680851 (-710 2210);
PAINT MONO (-710 2210);
FORCEPROP 2 LASTPIN (-700 2150) $PN 11
J 2
(-710 2160);
DISPLAY 0.680851 (-710 2160);
PAINT MONO (-710 2160);
FORCEPROP 2 LASTPIN (-700 2100) $PN 12
J 2
(-710 2110);
DISPLAY 0.680851 (-710 2110);
PAINT MONO (-710 2110);
FORCEPROP 2 LASTPIN (-700 2050) $PN 13
J 2
(-710 2060);
DISPLAY 0.680851 (-710 2060);
PAINT MONO (-710 2060);
FORCEPROP 2 LASTPIN (-700 2000) $PN 14
J 2
(-710 2010);
DISPLAY 0.680851 (-710 2010);
PAINT MONO (-710 2010);
FORCEPROP 2 LASTPIN (-700 1950) $PN 15
J 2
(-710 1960);
DISPLAY 0.680851 (-710 1960);
PAINT MONO (-710 1960);
FORCEPROP 2 LASTPIN (-700 1900) $PN 16
J 2
(-710 1910);
DISPLAY 0.680851 (-710 1910);
PAINT MONO (-710 1910);
FORCEPROP 2 LASTPIN (-700 1850) $PN 33
J 2
(-710 1860);
DISPLAY 0.680851 (-710 1860);
PAINT MONO (-710 1860);
FORCEPROP 2 LASTPIN (250 2250) $PN 1
J 0
(260 2260);
DISPLAY 0.680851 (260 2260);
PAINT MONO (260 2260);
FORCEPROP 2 LASTPIN (250 2200) $PN 2
J 0
(260 2210);
DISPLAY 0.680851 (260 2210);
PAINT MONO (260 2210);
FORCEPROP 2 LASTPIN (250 2150) $PN 25
J 0
(260 2160);
DISPLAY 0.680851 (260 2160);
PAINT MONO (260 2160);
FORCEPROP 2 LASTPIN (250 2100) $PN 26
J 0
(260 2110);
DISPLAY 0.680851 (260 2110);
PAINT MONO (260 2110);
FORCEPROP 2 LASTPIN (250 2050) $PN 27
J 0
(260 2060);
DISPLAY 0.680851 (260 2060);
PAINT MONO (260 2060);
FORCEPROP 2 LASTPIN (250 2000) $PN 28
J 0
(260 2010);
DISPLAY 0.680851 (260 2010);
PAINT MONO (260 2010);
FORCEPROP 2 LASTPIN (250 1950) $PN 29
J 0
(260 1960);
DISPLAY 0.680851 (260 1960);
PAINT MONO (260 1960);
FORCEPROP 2 LASTPIN (250 1900) $PN 30
J 0
(260 1910);
DISPLAY 0.680851 (260 1910);
PAINT MONO (260 1910);
FORCEPROP 2 LASTPIN (250 1850) $PN 31
J 0
(260 1860);
DISPLAY 0.680851 (260 1860);
PAINT MONO (260 1860);
FORCEPROP 2 LASTPIN (250 1800) $PN 32
J 0
(260 1810);
DISPLAY 0.680851 (260 1810);
PAINT MONO (260 1810);
FORCEPROP 2 LASTPIN (250 1050) $PN 18
J 0
(260 1060);
DISPLAY 0.680851 (260 1060);
PAINT MONO (260 1060);
FORCEPROP 2 LAST CDS_LIB pure_quanta
J 0
(-225 1525);
DISPLAY INVISIBLE (-225 1525);
FORCEPROP 1 LAST CDS_LMAN_SYM_OUTLINE -325,775,325,-775
J 0
(-225 1525);
DISPLAY 0.468085 (-225 1525);
PAINT GREEN (-225 1525);
DISPLAY INVISIBLE (-225 1525);
FORCEPROP 1 LAST NEEDS_NO_SIZE TRUE
J 0
(-225 1525);
DISPLAY 0.723404 (-225 1525);
PAINT GREEN (-225 1525);
DISPLAY INVISIBLE (-225 1525);
FORCEPROP 2 LAST SEC_TYPE 
J 0
(-525 2750);
DISPLAY 1.021277 (-525 2750);
DISPLAY INVISIBLE (-525 2750);
FORCEPROP 1 LAST PATH I35
J 0
(-225 1525);
DISPLAY 0.723404 (-225 1525);
PAINT GREEN (-225 1525);
DISPLAY INVISIBLE (-225 1525);
FORCEPROP 2 LAST SEC 1
J 0
(-525 2750);
DISPLAY 0.680851 (-525 2750);
PAINT MONO (-525 2750);
DISPLAY INVISIBLE (-525 2750);
FORCEADD UNIVERSAL_POWER..1
(-1200 2400);
FORCEPROP 3 LASTPIN (-1200 2350) SIG_NAME P12V_PSU\g
J 0
(-1190 2360);
DISPLAY 0.659574 (-1190 2360);
PAINT MONO (-1190 2360);
DISPLAY INVISIBLE (-1190 2360);
FORCEPROP 1 LAST HDL_POWER P12V_PSU
J 1
(-1200 2450);
DISPLAY 0.723404 (-1200 2450);
PAINT GREEN (-1200 2450);
FORCEPROP 2 LAST CDS_LIB logical_power
J 0
(-1200 2400);
DISPLAY INVISIBLE (-1200 2400);
FORCEPROP 2 LAST BOM_COST MIO_VRD_SB
J 0
(-1200 2500);
DISPLAY 0.617021 (-1200 2500);
PAINT PURPLE (-1200 2500);
DISPLAY INVISIBLE (-1200 2500);
FORCEPROP 2 LAST ROOM AUX_SW
J 0
(-1200 2500);
DISPLAY 0.617021 (-1200 2500);
DISPLAY INVISIBLE (-1200 2500);
FORCEPROP 1 LAST PATH I36
J 0
(-1150 2425);
DISPLAY 0.872340 (-1150 2425);
PAINT AQUA (-1150 2425);
DISPLAY INVISIBLE (-1150 2425);
FORCEADD Q_CAP..1
(750 -2000);
FORCEPROP 1 LAST PART_NUMBER CH3683K1B09
J 0
(800 -2125);
DISPLAY 0.723404 (800 -2125);
PAINT WHITE (800 -2125);
DISPLAY INVISIBLE (800 -2125);
FORCEPROP 1 LAST VALUE 0.068UF
J 0
(800 -1975);
DISPLAY 0.723404 (800 -1975);
PAINT SKYBLUE (800 -1975);
FORCEPROP 1 LAST VOLTAGE 16V
J 0
(800 -2025);
DISPLAY 0.723404 (800 -2025);
PAINT SKYBLUE (800 -2025);
FORCEPROP 1 LAST MATERIAL X7R
J 0
(800 -2075);
DISPLAY 0.723404 (800 -2075);
PAINT SKYBLUE (800 -2075);
FORCEPROP 1 LAST PACK_TYPE 0402
J 0
(800 -2175);
DISPLAY 0.723404 (800 -2175);
PAINT SKYBLUE (800 -2175);
FORCEPROP 2 LAST ROOM HSC1_BOM1
J 0
(800 -1875);
DISPLAY 1.021277 (800 -1875);
FORCEPROP 1 LAST LOCATION PC2185
J 0
(800 -1925);
DISPLAY 0.723404 (800 -1925);
PAINT AQUA (800 -1925);
FORCEPROP 1 LASTPIN (750 -1900) $PN 1
J 0
(760 -1920);
DISPLAY 0.787234 (760 -1920);
PAINT MONO (760 -1920);
FORCEPROP 1 LASTPIN (750 -2100) $PN 2
J 0
(760 -2120);
DISPLAY 0.787234 (760 -2120);
PAINT MONO (760 -2120);
FORCEPROP 2 LAST CDS_LIB pure_quanta
J 0
(750 -2000);
DISPLAY INVISIBLE (750 -2000);
FORCEPROP 1 LAST TOLERANCE 10%
J 0
(800 -2050);
DISPLAY 0.978723 (800 -2050);
PAINT SKYBLUE (800 -2050);
DISPLAY INVISIBLE (800 -2050);
FORCEPROP 1 LAST PATH I37
J 0
(800 -1850);
DISPLAY 0.978723 (800 -1850);
PAINT WHITE (800 -1850);
DISPLAY INVISIBLE (800 -1850);
FORCEPROP 0 LAST $SEC 1
J 0
(800 -1875);
DISPLAY 0.680851 (800 -1875);
PAINT MONO (800 -1875);
DISPLAY INVISIBLE (800 -1875);
FORCEPROP 0 LAST CDS_SEC 1
J 0
(800 -1875);
DISPLAY 1.021277 (800 -1875);
DISPLAY INVISIBLE (800 -1875);
FORCEADD UNIVERSAL_GND..1
(750 -2225);
FORCEPROP 3 LASTPIN (750 -2175) SIG_NAME AGND_HSC\g
J 0
(760 -2165);
DISPLAY 0.659574 (760 -2165);
PAINT MONO (760 -2165);
DISPLAY INVISIBLE (760 -2165);
FORCEPROP 1 LAST HDL_POWER AGND_HSC
J 1
(775 -2300);
DISPLAY 0.723404 (775 -2300);
PAINT GREEN (775 -2300);
FORCEPROP 2 LAST CDS_LIB logical_power
J 0
(750 -2225);
DISPLAY INVISIBLE (750 -2225);
FORCEPROP 1 LAST PATH I38
J 0
(825 -2225);
DISPLAY 0.872340 (825 -2225);
PAINT AQUA (825 -2225);
DISPLAY INVISIBLE (825 -2225);
FORCEADD Q_RES..1
(1250 -1275);
FORCEPROP 1 LAST PART_NUMBER CS00002JB13
J 0
(925 -1325);
DISPLAY 0.723404 (925 -1325);
PAINT WHITE (925 -1325);
DISPLAY INVISIBLE (925 -1325);
FORCEPROP 1 LAST TOLERANCE 5%
J 0
(1375 -1325);
DISPLAY 0.723404 (1375 -1325);
PAINT SKYBLUE (1375 -1325);
FORCEPROP 1 LAST PACK_TYPE 0402LF
J 0
(1175 -1375);
DISPLAY 0.723404 (1175 -1375);
PAINT SKYBLUE (1175 -1375);
FORCEPROP 1 LAST VALUE 0
J 2
(1400 -1250);
DISPLAY 0.723404 (1400 -1250);
PAINT SKYBLUE (1400 -1250);
FORCEPROP 1 LAST WATTAGE 1/16W
J 2
(1125 -1375);
DISPLAY 0.723404 (1125 -1375);
PAINT SKYBLUE (1125 -1375);
FORCEPROP 1 LAST MATERIAL CHIP
J 0
(1425 -1375);
DISPLAY 0.723404 (1425 -1375);
PAINT SKYBLUE (1425 -1375);
FORCEPROP 2 LAST ROOM HSC1_BOM1
J 0
(1400 -1200);
DISPLAY 1.021277 (1400 -1200);
FORCEPROP 1 LAST LOCATION PR3921
J 0
(950 -1275);
DISPLAY 0.723404 (950 -1275);
PAINT AQUA (950 -1275);
FORCEPROP 1 LASTPIN (1150 -1275) $PN 1
J 0
(1162 -1263);
DISPLAY 0.787234 (1162 -1263);
PAINT MONO (1162 -1263);
FORCEPROP 1 LASTPIN (1350 -1275) $PN 2
J 0
(1312 -1263);
DISPLAY 0.787234 (1312 -1263);
PAINT MONO (1312 -1263);
FORCEPROP 2 LAST CDS_LIB pure_quanta
J 0
(1250 -1275);
DISPLAY INVISIBLE (1250 -1275);
FORCEPROP 1 LAST PATH I39
J 0
(1200 -1125);
DISPLAY 0.978723 (1200 -1125);
PAINT WHITE (1200 -1125);
DISPLAY INVISIBLE (1200 -1125);
FORCEPROP 0 LAST $SEC 1
J 0
(1400 -1200);
DISPLAY 0.680851 (1400 -1200);
PAINT MONO (1400 -1200);
DISPLAY INVISIBLE (1400 -1200);
FORCEPROP 0 LAST CDS_SEC 1
J 0
(1400 -1200);
DISPLAY 1.021277 (1400 -1200);
DISPLAY INVISIBLE (1400 -1200);
FORCEADD Q_CAP..1
(-3700 -1375);
FORCEPROP 1 LAST PART_NUMBER CH5104KEB02
J 0
(-3625 -1425);
DISPLAY 0.723404 (-3625 -1425);
PAINT WHITE (-3625 -1425);
DISPLAY INVISIBLE (-3625 -1425);
FORCEPROP 1 LAST VALUE 1UF
J 0
(-3625 -1275);
DISPLAY 0.723404 (-3625 -1275);
PAINT SKYBLUE (-3625 -1275);
FORCEPROP 1 LAST PACK_TYPE C0402
J 0
(-3625 -1475);
DISPLAY 0.723404 (-3625 -1475);
PAINT SKYBLUE (-3625 -1475);
FORCEPROP 1 LAST MATERIAL X6S
J 0
(-3625 -1375);
DISPLAY 0.723404 (-3625 -1375);
PAINT SKYBLUE (-3625 -1375);
FORCEPROP 1 LAST VOLTAGE 25V
J 0
(-3625 -1325);
DISPLAY 0.723404 (-3625 -1325);
PAINT SKYBLUE (-3625 -1325);
FORCEPROP 2 LAST ROOM HSC1_BOM1
J 0
(-3625 -1175);
DISPLAY 1.021277 (-3625 -1175);
FORCEPROP 1 LAST LOCATION PC2181
J 0
(-3625 -1225);
DISPLAY 0.723404 (-3625 -1225);
PAINT AQUA (-3625 -1225);
FORCEPROP 1 LASTPIN (-3700 -1275) $PN 1
J 0
(-3690 -1295);
DISPLAY 0.787234 (-3690 -1295);
PAINT MONO (-3690 -1295);
FORCEPROP 1 LASTPIN (-3700 -1475) $PN 2
J 0
(-3690 -1495);
DISPLAY 0.787234 (-3690 -1495);
PAINT MONO (-3690 -1495);
FORCEPROP 2 LAST CDS_LIB pure_quanta
J 0
(-3700 -1375);
DISPLAY INVISIBLE (-3700 -1375);
FORCEPROP 1 LAST TOLERANCE 10%
J 0
(-3650 -1425);
DISPLAY 0.978723 (-3650 -1425);
PAINT SKYBLUE (-3650 -1425);
DISPLAY INVISIBLE (-3650 -1425);
FORCEPROP 1 LAST PATH I4
J 0
(-3650 -1225);
DISPLAY 0.978723 (-3650 -1225);
PAINT WHITE (-3650 -1225);
DISPLAY INVISIBLE (-3650 -1225);
FORCEPROP 0 LAST $SEC 1
J 0
(-3625 -1175);
DISPLAY 0.680851 (-3625 -1175);
PAINT MONO (-3625 -1175);
DISPLAY INVISIBLE (-3625 -1175);
FORCEPROP 0 LAST CDS_SEC 1
J 0
(-3625 -1175);
DISPLAY 1.021277 (-3625 -1175);
DISPLAY INVISIBLE (-3625 -1175);
FORCEADD Q_RES..1
(1250 -1450);
FORCEPROP 1 LAST PART_NUMBER CS00002JB13
J 0
(925 -1500);
DISPLAY 0.723404 (925 -1500);
PAINT WHITE (925 -1500);
DISPLAY INVISIBLE (925 -1500);
FORCEPROP 1 LAST VALUE 0
J 2
(1400 -1425);
DISPLAY 0.723404 (1400 -1425);
PAINT SKYBLUE (1400 -1425);
FORCEPROP 1 LAST TOLERANCE 5%
J 0
(1375 -1500);
DISPLAY 0.723404 (1375 -1500);
PAINT SKYBLUE (1375 -1500);
FORCEPROP 1 LAST MATERIAL CHIP
J 0
(1425 -1550);
DISPLAY 0.723404 (1425 -1550);
PAINT SKYBLUE (1425 -1550);
FORCEPROP 1 LAST WATTAGE 1/16W
J 2
(1125 -1550);
DISPLAY 0.723404 (1125 -1550);
PAINT SKYBLUE (1125 -1550);
FORCEPROP 1 LAST PACK_TYPE 0402LF
J 0
(1175 -1550);
DISPLAY 0.723404 (1175 -1550);
PAINT SKYBLUE (1175 -1550);
FORCEPROP 2 LAST ROOM HSC1_BOM1
J 0
(1400 -1375);
DISPLAY 1.021277 (1400 -1375);
FORCEPROP 1 LAST LOCATION PR3922
J 0
(950 -1450);
DISPLAY 0.723404 (950 -1450);
PAINT AQUA (950 -1450);
FORCEPROP 1 LASTPIN (1150 -1450) $PN 1
J 0
(1162 -1438);
DISPLAY 0.787234 (1162 -1438);
PAINT MONO (1162 -1438);
FORCEPROP 1 LASTPIN (1350 -1450) $PN 2
J 0
(1312 -1438);
DISPLAY 0.787234 (1312 -1438);
PAINT MONO (1312 -1438);
FORCEPROP 2 LAST CDS_LIB pure_quanta
J 0
(1250 -1450);
DISPLAY INVISIBLE (1250 -1450);
FORCEPROP 1 LAST PATH I40
J 0
(1200 -1300);
DISPLAY 0.978723 (1200 -1300);
PAINT WHITE (1200 -1300);
DISPLAY INVISIBLE (1200 -1300);
FORCEPROP 0 LAST $SEC 1
J 0
(1400 -1375);
DISPLAY 0.680851 (1400 -1375);
PAINT MONO (1400 -1375);
DISPLAY INVISIBLE (1400 -1375);
FORCEPROP 0 LAST CDS_SEC 1
J 0
(1400 -1375);
DISPLAY 1.021277 (1400 -1375);
DISPLAY INVISIBLE (1400 -1375);
FORCEADD UNIVERSAL_POWER..1
(875 -400);
FORCEPROP 3 LASTPIN (875 -450) SIG_NAME P12V_AUX\g
J 0
(885 -440);
DISPLAY 0.659574 (885 -440);
PAINT MONO (885 -440);
DISPLAY INVISIBLE (885 -440);
FORCEPROP 1 LAST HDL_POWER P12V_AUX
J 1
(875 -350);
DISPLAY 0.723404 (875 -350);
PAINT GREEN (875 -350);
FORCEPROP 2 LAST BOM_COST MIO_VRD_SB
J 0
(875 -300);
DISPLAY 0.617021 (875 -300);
PAINT PURPLE (875 -300);
DISPLAY INVISIBLE (875 -300);
FORCEPROP 2 LAST CDS_LIB logical_power
J 0
(875 -400);
DISPLAY INVISIBLE (875 -400);
FORCEPROP 2 LAST ROOM AUX_SW
J 0
(875 -300);
DISPLAY 0.617021 (875 -300);
DISPLAY INVISIBLE (875 -300);
FORCEPROP 1 LAST PATH I41
J 0
(925 -375);
DISPLAY 0.872340 (925 -375);
PAINT AQUA (925 -375);
DISPLAY INVISIBLE (925 -375);
FORCEADD OFFPAGE..5
R 2
(2025 -1750);
FORCEPROP 2 LAST $XR2 301 
J 0
(2454 -1750);
DISPLAY 0.638298 (2454 -1750);
PAINT MONO (2454 -1750);
FORCEPROP 2 LAST $XR1 303 
J 0
(2334 -1750);
DISPLAY 0.638298 (2334 -1750);
PAINT MONO (2334 -1750);
FORCEPROP 2 LAST $XR0 302 
J 0
(2214 -1750);
DISPLAY 0.638298 (2214 -1750);
PAINT MONO (2214 -1750);
FORCEPROP 2 LAST CDS_LIB standard
J 2
(2025 -1750);
DISPLAY INVISIBLE (2025 -1750);
FORCEPROP 1 LAST OFFPAGE TRUE
J 2
(1700 -1875);
DISPLAY 0.872340 (1700 -1875);
PAINT AQUA (1700 -1875);
DISPLAY INVISIBLE (1700 -1875);
FORCEPROP 1 LAST COMMENT_BODY TRUE
J 2
(1925 -1825);
DISPLAY 1.170213 (1925 -1825);
PAINT GREEN (1925 -1825);
DISPLAY INVISIBLE (1925 -1825);
FORCEPROP 2 LAST PATH I42
J 0
(2475 -1700);
DISPLAY 1.021277 (2475 -1700);
DISPLAY INVISIBLE (2475 -1700);
FORCEADD OFFPAGE..4
(2025 -1850);
FORCEPROP 2 LAST $XR2 303 
J 0
(2451 -1850);
DISPLAY 0.638298 (2451 -1850);
PAINT MONO (2451 -1850);
FORCEPROP 2 LAST $XR1 302 
J 0
(2331 -1850);
DISPLAY 0.638298 (2331 -1850);
PAINT MONO (2331 -1850);
FORCEPROP 2 LAST $XR0 301 
J 0
(2211 -1850);
DISPLAY 0.638298 (2211 -1850);
PAINT MONO (2211 -1850);
FORCEPROP 2 LAST CDS_LIB standard
J 0
(2025 -1850);
DISPLAY INVISIBLE (2025 -1850);
FORCEPROP 1 LAST OFFPAGE TRUE
J 0
(2350 -1975);
DISPLAY 0.872340 (2350 -1975);
PAINT GREEN (2350 -1975);
DISPLAY INVISIBLE (2350 -1975);
FORCEPROP 1 LAST COMMENT_BODY TRUE
J 0
(2000 -1950);
DISPLAY 0.872340 (2000 -1950);
PAINT GREEN (2000 -1950);
DISPLAY INVISIBLE (2000 -1950);
FORCEPROP 2 LAST PATH I43
J 0
(2475 -1800);
DISPLAY 1.021277 (2475 -1800);
DISPLAY INVISIBLE (2475 -1800);
FORCEADD OFFPAGE..5
R 2
(2025 -1650);
FORCEPROP 2 LAST $XR2 301 
J 0
(2454 -1650);
DISPLAY 0.638298 (2454 -1650);
PAINT MONO (2454 -1650);
FORCEPROP 2 LAST $XR1 303 
J 0
(2334 -1650);
DISPLAY 0.638298 (2334 -1650);
PAINT MONO (2334 -1650);
FORCEPROP 2 LAST $XR0 302 
J 0
(2214 -1650);
DISPLAY 0.638298 (2214 -1650);
PAINT MONO (2214 -1650);
FORCEPROP 2 LAST CDS_LIB standard
J 2
(2025 -1650);
DISPLAY INVISIBLE (2025 -1650);
FORCEPROP 1 LAST OFFPAGE TRUE
J 2
(1700 -1775);
DISPLAY 0.872340 (1700 -1775);
PAINT AQUA (1700 -1775);
DISPLAY INVISIBLE (1700 -1775);
FORCEPROP 1 LAST COMMENT_BODY TRUE
J 2
(1925 -1725);
DISPLAY 1.170213 (1925 -1725);
PAINT GREEN (1925 -1725);
DISPLAY INVISIBLE (1925 -1725);
FORCEPROP 2 LAST PATH I44
J 0
(2475 -1600);
DISPLAY 1.021277 (2475 -1600);
DISPLAY INVISIBLE (2475 -1600);
FORCEADD OFFPAGE..4
(2025 -1450);
FORCEPROP 2 LAST $XR2 303 
J 0
(2451 -1450);
DISPLAY 0.638298 (2451 -1450);
PAINT MONO (2451 -1450);
FORCEPROP 2 LAST $XR1 302 
J 0
(2331 -1450);
DISPLAY 0.638298 (2331 -1450);
PAINT MONO (2331 -1450);
FORCEPROP 2 LAST $XR0 301 
J 0
(2211 -1450);
DISPLAY 0.638298 (2211 -1450);
PAINT MONO (2211 -1450);
FORCEPROP 2 LAST CDS_LIB standard
J 0
(2025 -1450);
DISPLAY INVISIBLE (2025 -1450);
FORCEPROP 1 LAST OFFPAGE TRUE
J 0
(2350 -1575);
DISPLAY 0.872340 (2350 -1575);
PAINT GREEN (2350 -1575);
DISPLAY INVISIBLE (2350 -1575);
FORCEPROP 1 LAST COMMENT_BODY TRUE
J 0
(2000 -1550);
DISPLAY 0.872340 (2000 -1550);
PAINT GREEN (2000 -1550);
DISPLAY INVISIBLE (2000 -1550);
FORCEPROP 2 LAST PATH I45
J 0
(2475 -1400);
DISPLAY 1.021277 (2475 -1400);
DISPLAY INVISIBLE (2475 -1400);
FORCEADD OFFPAGE..5
R 2
(2025 -1275);
FORCEPROP 2 LAST $XR2 301 
J 0
(2454 -1275);
DISPLAY 0.638298 (2454 -1275);
PAINT MONO (2454 -1275);
FORCEPROP 2 LAST $XR1 303 
J 0
(2334 -1275);
DISPLAY 0.638298 (2334 -1275);
PAINT MONO (2334 -1275);
FORCEPROP 2 LAST $XR0 302 
J 0
(2214 -1275);
DISPLAY 0.638298 (2214 -1275);
PAINT MONO (2214 -1275);
FORCEPROP 2 LAST CDS_LIB standard
J 0
(2025 -1275);
DISPLAY INVISIBLE (2025 -1275);
FORCEPROP 1 LAST OFFPAGE TRUE
J 2
(1700 -1400);
DISPLAY 0.872340 (1700 -1400);
PAINT AQUA (1700 -1400);
DISPLAY INVISIBLE (1700 -1400);
FORCEPROP 1 LAST COMMENT_BODY TRUE
J 2
(1925 -1350);
DISPLAY 1.170213 (1925 -1350);
PAINT GREEN (1925 -1350);
DISPLAY INVISIBLE (1925 -1350);
FORCEPROP 2 LAST PATH I46
J 0
(2475 -1225);
DISPLAY 1.021277 (2475 -1225);
DISPLAY INVISIBLE (2475 -1225);
FORCEADD Q_CAP..1
(750 800);
FORCEPROP 1 LAST PART_NUMBER CH3683K1B09
J 0
(800 675);
DISPLAY 0.723404 (800 675);
PAINT WHITE (800 675);
DISPLAY INVISIBLE (800 675);
FORCEPROP 1 LAST VALUE 0.068UF
J 0
(800 825);
DISPLAY 0.723404 (800 825);
PAINT SKYBLUE (800 825);
FORCEPROP 1 LAST MATERIAL X7R
J 0
(800 725);
DISPLAY 0.723404 (800 725);
PAINT SKYBLUE (800 725);
FORCEPROP 1 LAST PACK_TYPE 0402
J 0
(800 625);
DISPLAY 0.723404 (800 625);
PAINT SKYBLUE (800 625);
FORCEPROP 1 LAST VOLTAGE 16V
J 0
(800 775);
DISPLAY 0.723404 (800 775);
PAINT SKYBLUE (800 775);
FORCEPROP 2 LAST ROOM HSC1_BOM1
J 0
(800 925);
DISPLAY 1.021277 (800 925);
FORCEPROP 1 LAST LOCATION PC2184
J 0
(800 875);
DISPLAY 0.723404 (800 875);
PAINT AQUA (800 875);
FORCEPROP 1 LASTPIN (750 900) $PN 1
J 0
(760 880);
DISPLAY 0.787234 (760 880);
PAINT MONO (760 880);
FORCEPROP 1 LASTPIN (750 700) $PN 2
J 0
(760 680);
DISPLAY 0.787234 (760 680);
PAINT MONO (760 680);
FORCEPROP 2 LAST CDS_LIB pure_quanta
J 0
(750 800);
DISPLAY INVISIBLE (750 800);
FORCEPROP 1 LAST TOLERANCE 10%
J 0
(800 750);
DISPLAY 0.978723 (800 750);
PAINT SKYBLUE (800 750);
DISPLAY INVISIBLE (800 750);
FORCEPROP 1 LAST PATH I47
J 0
(800 950);
DISPLAY 0.978723 (800 950);
PAINT WHITE (800 950);
DISPLAY INVISIBLE (800 950);
FORCEPROP 0 LAST $SEC 1
J 0
(800 925);
DISPLAY 0.680851 (800 925);
PAINT MONO (800 925);
DISPLAY INVISIBLE (800 925);
FORCEPROP 0 LAST CDS_SEC 1
J 0
(800 925);
DISPLAY 1.021277 (800 925);
DISPLAY INVISIBLE (800 925);
FORCEADD UNIVERSAL_GND..1
(750 575);
FORCEPROP 3 LASTPIN (750 625) SIG_NAME AGND_HSC\g
J 0
(760 635);
DISPLAY 0.659574 (760 635);
PAINT MONO (760 635);
DISPLAY INVISIBLE (760 635);
FORCEPROP 1 LAST HDL_POWER AGND_HSC
J 1
(775 500);
DISPLAY 0.723404 (775 500);
PAINT GREEN (775 500);
FORCEPROP 2 LAST CDS_LIB logical_power
J 0
(750 575);
DISPLAY INVISIBLE (750 575);
FORCEPROP 1 LAST PATH I48
J 0
(825 575);
DISPLAY 0.872340 (825 575);
PAINT AQUA (825 575);
DISPLAY INVISIBLE (825 575);
FORCEADD Q_RES..1
(1250 1525);
FORCEPROP 1 LAST PART_NUMBER CS00002JB13
J 0
(925 1475);
DISPLAY 0.723404 (925 1475);
PAINT WHITE (925 1475);
DISPLAY INVISIBLE (925 1475);
FORCEPROP 1 LAST VALUE 0
J 2
(1400 1550);
DISPLAY 0.723404 (1400 1550);
PAINT SKYBLUE (1400 1550);
FORCEPROP 1 LAST TOLERANCE 5%
J 0
(1375 1475);
DISPLAY 0.723404 (1375 1475);
PAINT SKYBLUE (1375 1475);
FORCEPROP 1 LAST MATERIAL CHIP
J 0
(1425 1425);
DISPLAY 0.723404 (1425 1425);
PAINT SKYBLUE (1425 1425);
FORCEPROP 2 LAST ROOM HSC1_BOM1
J 0
(1400 1600);
DISPLAY 1.021277 (1400 1600);
FORCEPROP 1 LAST PACK_TYPE 0402LF
J 0
(1175 1425);
DISPLAY 0.723404 (1175 1425);
PAINT SKYBLUE (1175 1425);
FORCEPROP 1 LAST WATTAGE 1/16W
J 2
(1125 1425);
DISPLAY 0.723404 (1125 1425);
PAINT SKYBLUE (1125 1425);
FORCEPROP 1 LAST LOCATION PR3919
J 0
(950 1525);
DISPLAY 0.723404 (950 1525);
PAINT AQUA (950 1525);
FORCEPROP 1 LASTPIN (1150 1525) $PN 1
J 0
(1162 1537);
DISPLAY 0.787234 (1162 1537);
PAINT MONO (1162 1537);
FORCEPROP 1 LASTPIN (1350 1525) $PN 2
J 0
(1312 1537);
DISPLAY 0.787234 (1312 1537);
PAINT MONO (1312 1537);
FORCEPROP 2 LAST CDS_LIB pure_quanta
J 0
(1250 1525);
DISPLAY INVISIBLE (1250 1525);
FORCEPROP 1 LAST PATH I49
J 0
(1200 1675);
DISPLAY 0.978723 (1200 1675);
PAINT WHITE (1200 1675);
DISPLAY INVISIBLE (1200 1675);
FORCEPROP 0 LAST $SEC 1
J 0
(1400 1600);
DISPLAY 0.680851 (1400 1600);
PAINT MONO (1400 1600);
DISPLAY INVISIBLE (1400 1600);
FORCEPROP 0 LAST CDS_SEC 1
J 0
(1400 1600);
DISPLAY 1.021277 (1400 1600);
DISPLAY INVISIBLE (1400 1600);
FORCEADD Q_RES..1
R 1
(-3700 -900);
FORCEPROP 1 LAST PART_NUMBER CS00002JB13
J 0
(-3625 -1000);
DISPLAY 0.723404 (-3625 -1000);
PAINT WHITE (-3625 -1000);
DISPLAY INVISIBLE (-3625 -1000);
FORCEPROP 1 LAST TOLERANCE 5%
J 0
(-3625 -850);
DISPLAY 0.723404 (-3625 -850);
PAINT SKYBLUE (-3625 -850);
FORCEPROP 1 LAST MATERIAL CHIP
J 0
(-3625 -900);
DISPLAY 0.787234 (-3625 -900);
PAINT SKYBLUE (-3625 -900);
FORCEPROP 1 LAST WATTAGE 1/16W
J 0
(-3625 -950);
DISPLAY 0.723404 (-3625 -950);
PAINT SKYBLUE (-3625 -950);
FORCEPROP 1 LAST PACK_TYPE 0402LF
J 0
(-3625 -1050);
DISPLAY 0.723404 (-3625 -1050);
PAINT SKYBLUE (-3625 -1050);
FORCEPROP 1 LAST VALUE 0
R 2
J 0
(-3600 -775);
DISPLAY 0.723404 (-3600 -775);
PAINT SKYBLUE (-3600 -775);
FORCEPROP 2 LAST ROOM HSC1_BOM1
J 0
(-3625 -700);
DISPLAY 1.021277 (-3625 -700);
FORCEPROP 1 LAST LOCATION PR3911
J 0
(-3625 -750);
DISPLAY 0.723404 (-3625 -750);
PAINT AQUA (-3625 -750);
FORCEPROP 1 LASTPIN (-3700 -1000) $PN 1
R 1
J 0
(-3712 -988);
DISPLAY 0.787234 (-3712 -988);
PAINT MONO (-3712 -988);
FORCEPROP 1 LASTPIN (-3700 -800) $PN 2
R 1
J 0
(-3712 -838);
DISPLAY 0.787234 (-3712 -838);
PAINT MONO (-3712 -838);
FORCEPROP 2 LAST CDS_LIB pure_quanta
J 0
(-3700 -900);
DISPLAY INVISIBLE (-3700 -900);
FORCEPROP 1 LAST PATH I5
R 1
J 0
(-3850 -950);
DISPLAY 0.978723 (-3850 -950);
PAINT WHITE (-3850 -950);
DISPLAY INVISIBLE (-3850 -950);
FORCEPROP 0 LAST $SEC 1
R 1
J 0
(-3625 -700);
DISPLAY 0.680851 (-3625 -700);
PAINT MONO (-3625 -700);
DISPLAY INVISIBLE (-3625 -700);
FORCEPROP 0 LAST CDS_SEC 1
R 1
J 0
(-3625 -700);
DISPLAY 1.021277 (-3625 -700);
DISPLAY INVISIBLE (-3625 -700);
FORCEADD Q_RES..1
(1250 1350);
FORCEPROP 1 LAST PART_NUMBER CS00002JB13
J 0
(925 1300);
DISPLAY 0.723404 (925 1300);
PAINT WHITE (925 1300);
DISPLAY INVISIBLE (925 1300);
FORCEPROP 1 LAST VALUE 0
J 2
(1400 1375);
DISPLAY 0.723404 (1400 1375);
PAINT SKYBLUE (1400 1375);
FORCEPROP 2 LAST ROOM HSC1_BOM1
J 0
(1400 1425);
DISPLAY 1.021277 (1400 1425);
FORCEPROP 1 LAST PACK_TYPE 0402LF
J 0
(1175 1250);
DISPLAY 0.723404 (1175 1250);
PAINT SKYBLUE (1175 1250);
FORCEPROP 1 LAST MATERIAL CHIP
J 0
(1425 1250);
DISPLAY 0.723404 (1425 1250);
PAINT SKYBLUE (1425 1250);
FORCEPROP 1 LAST TOLERANCE 5%
J 0
(1375 1300);
DISPLAY 0.723404 (1375 1300);
PAINT SKYBLUE (1375 1300);
FORCEPROP 1 LAST WATTAGE 1/16W
J 2
(1125 1250);
DISPLAY 0.723404 (1125 1250);
PAINT SKYBLUE (1125 1250);
FORCEPROP 1 LAST LOCATION PR3920
J 0
(950 1350);
DISPLAY 0.723404 (950 1350);
PAINT AQUA (950 1350);
FORCEPROP 1 LASTPIN (1150 1350) $PN 1
J 0
(1162 1362);
DISPLAY 0.787234 (1162 1362);
PAINT MONO (1162 1362);
FORCEPROP 1 LASTPIN (1350 1350) $PN 2
J 0
(1312 1362);
DISPLAY 0.787234 (1312 1362);
PAINT MONO (1312 1362);
FORCEPROP 2 LAST CDS_LIB pure_quanta
J 0
(1250 1350);
DISPLAY INVISIBLE (1250 1350);
FORCEPROP 1 LAST PATH I50
J 0
(1200 1500);
DISPLAY 0.978723 (1200 1500);
PAINT WHITE (1200 1500);
DISPLAY INVISIBLE (1200 1500);
FORCEPROP 0 LAST $SEC 1
J 0
(1400 1425);
DISPLAY 0.680851 (1400 1425);
PAINT MONO (1400 1425);
DISPLAY INVISIBLE (1400 1425);
FORCEPROP 0 LAST CDS_SEC 1
J 0
(1400 1425);
DISPLAY 1.021277 (1400 1425);
DISPLAY INVISIBLE (1400 1425);
FORCEADD UNIVERSAL_POWER..1
(875 2400);
FORCEPROP 3 LASTPIN (875 2350) SIG_NAME P12V_AUX\g
J 0
(885 2360);
DISPLAY 0.659574 (885 2360);
PAINT MONO (885 2360);
DISPLAY INVISIBLE (885 2360);
FORCEPROP 1 LAST HDL_POWER P12V_AUX
J 1
(875 2450);
DISPLAY 0.723404 (875 2450);
PAINT GREEN (875 2450);
FORCEPROP 2 LAST CDS_LIB logical_power
J 0
(875 2400);
DISPLAY INVISIBLE (875 2400);
FORCEPROP 2 LAST BOM_COST MIO_VRD_SB
J 0
(875 2500);
DISPLAY 0.617021 (875 2500);
PAINT PURPLE (875 2500);
DISPLAY INVISIBLE (875 2500);
FORCEPROP 2 LAST ROOM AUX_SW
J 0
(875 2500);
DISPLAY 0.617021 (875 2500);
DISPLAY INVISIBLE (875 2500);
FORCEPROP 1 LAST PATH I51
J 0
(925 2425);
DISPLAY 0.872340 (925 2425);
PAINT AQUA (925 2425);
DISPLAY INVISIBLE (925 2425);
FORCEADD OFFPAGE..4
(2050 950);
FORCEPROP 2 LAST $XR2 303 
J 0
(2476 950);
DISPLAY 0.638298 (2476 950);
PAINT MONO (2476 950);
FORCEPROP 2 LAST $XR1 302 
J 0
(2356 950);
DISPLAY 0.638298 (2356 950);
PAINT MONO (2356 950);
FORCEPROP 2 LAST $XR0 301 
J 0
(2236 950);
DISPLAY 0.638298 (2236 950);
PAINT MONO (2236 950);
FORCEPROP 2 LAST CDS_LIB standard
J 0
(2050 950);
DISPLAY INVISIBLE (2050 950);
FORCEPROP 1 LAST OFFPAGE TRUE
J 0
(2375 825);
DISPLAY 0.872340 (2375 825);
PAINT GREEN (2375 825);
DISPLAY INVISIBLE (2375 825);
FORCEPROP 1 LAST COMMENT_BODY TRUE
J 0
(2025 850);
DISPLAY 0.872340 (2025 850);
PAINT GREEN (2025 850);
DISPLAY INVISIBLE (2025 850);
FORCEPROP 2 LAST PATH I52
J 0
(2500 1000);
DISPLAY 1.021277 (2500 1000);
DISPLAY INVISIBLE (2500 1000);
FORCEADD OFFPAGE..5
R 2
(2050 1050);
FORCEPROP 2 LAST $XR2 301 
J 0
(2479 1050);
DISPLAY 0.638298 (2479 1050);
PAINT MONO (2479 1050);
FORCEPROP 2 LAST $XR1 303 
J 0
(2359 1050);
DISPLAY 0.638298 (2359 1050);
PAINT MONO (2359 1050);
FORCEPROP 2 LAST $XR0 302 
J 0
(2239 1050);
DISPLAY 0.638298 (2239 1050);
PAINT MONO (2239 1050);
FORCEPROP 2 LAST CDS_LIB standard
J 2
(2050 1050);
DISPLAY INVISIBLE (2050 1050);
FORCEPROP 1 LAST OFFPAGE TRUE
J 2
(1725 925);
DISPLAY 0.872340 (1725 925);
PAINT AQUA (1725 925);
DISPLAY INVISIBLE (1725 925);
FORCEPROP 1 LAST COMMENT_BODY TRUE
J 2
(1950 975);
DISPLAY 1.170213 (1950 975);
PAINT GREEN (1950 975);
DISPLAY INVISIBLE (1950 975);
FORCEPROP 2 LAST PATH I53
J 0
(2500 1100);
DISPLAY 1.021277 (2500 1100);
DISPLAY INVISIBLE (2500 1100);
FORCEADD OFFPAGE..5
R 2
(2050 1150);
FORCEPROP 2 LAST $XR2 301 
J 0
(2479 1150);
DISPLAY 0.638298 (2479 1150);
PAINT MONO (2479 1150);
FORCEPROP 2 LAST $XR1 303 
J 0
(2359 1150);
DISPLAY 0.638298 (2359 1150);
PAINT MONO (2359 1150);
FORCEPROP 2 LAST $XR0 302 
J 0
(2239 1150);
DISPLAY 0.638298 (2239 1150);
PAINT MONO (2239 1150);
FORCEPROP 2 LAST CDS_LIB standard
J 2
(2050 1150);
DISPLAY INVISIBLE (2050 1150);
FORCEPROP 1 LAST OFFPAGE TRUE
J 2
(1725 1025);
DISPLAY 0.872340 (1725 1025);
PAINT AQUA (1725 1025);
DISPLAY INVISIBLE (1725 1025);
FORCEPROP 1 LAST COMMENT_BODY TRUE
J 2
(1950 1075);
DISPLAY 1.170213 (1950 1075);
PAINT GREEN (1950 1075);
DISPLAY INVISIBLE (1950 1075);
FORCEPROP 2 LAST PATH I54
J 0
(2500 1200);
DISPLAY 1.021277 (2500 1200);
DISPLAY INVISIBLE (2500 1200);
FORCEADD OFFPAGE..4
(2050 1350);
FORCEPROP 2 LAST $XR2 303 
J 0
(2476 1350);
DISPLAY 0.638298 (2476 1350);
PAINT MONO (2476 1350);
FORCEPROP 2 LAST $XR1 302 
J 0
(2356 1350);
DISPLAY 0.638298 (2356 1350);
PAINT MONO (2356 1350);
FORCEPROP 2 LAST $XR0 301 
J 0
(2236 1350);
DISPLAY 0.638298 (2236 1350);
PAINT MONO (2236 1350);
FORCEPROP 2 LAST CDS_LIB standard
J 0
(2050 1350);
DISPLAY INVISIBLE (2050 1350);
FORCEPROP 1 LAST OFFPAGE TRUE
J 0
(2375 1225);
DISPLAY 0.872340 (2375 1225);
PAINT GREEN (2375 1225);
DISPLAY INVISIBLE (2375 1225);
FORCEPROP 1 LAST COMMENT_BODY TRUE
J 0
(2025 1250);
DISPLAY 0.872340 (2025 1250);
PAINT GREEN (2025 1250);
DISPLAY INVISIBLE (2025 1250);
FORCEPROP 2 LAST PATH I55
J 0
(2500 1400);
DISPLAY 1.021277 (2500 1400);
DISPLAY INVISIBLE (2500 1400);
FORCEADD OFFPAGE..5
R 2
(2050 1525);
FORCEPROP 2 LAST $XR2 301 
J 0
(2479 1525);
DISPLAY 0.638298 (2479 1525);
PAINT MONO (2479 1525);
FORCEPROP 2 LAST $XR1 303 
J 0
(2359 1525);
DISPLAY 0.638298 (2359 1525);
PAINT MONO (2359 1525);
FORCEPROP 2 LAST $XR0 302 
J 0
(2239 1525);
DISPLAY 0.638298 (2239 1525);
PAINT MONO (2239 1525);
FORCEPROP 2 LAST CDS_LIB standard
J 0
(2050 1525);
DISPLAY INVISIBLE (2050 1525);
FORCEPROP 1 LAST OFFPAGE TRUE
J 2
(1725 1400);
DISPLAY 0.872340 (1725 1400);
PAINT AQUA (1725 1400);
DISPLAY INVISIBLE (1725 1400);
FORCEPROP 1 LAST COMMENT_BODY TRUE
J 2
(1950 1450);
DISPLAY 1.170213 (1950 1450);
PAINT GREEN (1950 1450);
DISPLAY INVISIBLE (1950 1450);
FORCEPROP 2 LAST PATH I56
J 0
(2500 1575);
DISPLAY 1.021277 (2500 1575);
DISPLAY INVISIBLE (2500 1575);
FORCEADD UNIVERSAL_POWER..1
(-3700 -650);
FORCEPROP 3 LASTPIN (-3700 -700) SIG_NAME HSC_VDD\g
J 0
(-3690 -690);
DISPLAY 0.659574 (-3690 -690);
PAINT MONO (-3690 -690);
DISPLAY INVISIBLE (-3690 -690);
FORCEPROP 1 LAST HDL_POWER HSC_VDD
J 1
(-3700 -600);
DISPLAY 0.723404 (-3700 -600);
PAINT GREEN (-3700 -600);
FORCEPROP 2 LAST CDS_LIB logical_power
J 0
(-3700 -650);
DISPLAY INVISIBLE (-3700 -650);
FORCEPROP 2 LAST BOM_COST MIO_VRD_SB
J 0
(-3700 -550);
DISPLAY 0.617021 (-3700 -550);
PAINT PURPLE (-3700 -550);
DISPLAY INVISIBLE (-3700 -550);
FORCEPROP 2 LAST ROOM AUX_SW
J 0
(-3700 -550);
DISPLAY 0.617021 (-3700 -550);
DISPLAY INVISIBLE (-3700 -550);
FORCEPROP 1 LAST PATH I6
J 0
(-3650 -625);
DISPLAY 0.872340 (-3650 -625);
PAINT AQUA (-3650 -625);
DISPLAY INVISIBLE (-3650 -625);
FORCEADD OFFPAGE..4
R 2
(-3000 -1500);
FORCEPROP 2 LAST $XR2 303 
J 0
(-3282 -1536);
DISPLAY 0.638298 (-3282 -1536);
PAINT MONO (-3282 -1536);
FORCEPROP 2 LAST $XR1 302 
J 0
(-3402 -1500);
DISPLAY 0.638298 (-3402 -1500);
PAINT MONO (-3402 -1500);
FORCEPROP 2 LAST $XR0 301 
J 0
(-3282 -1500);
DISPLAY 0.638298 (-3282 -1500);
PAINT MONO (-3282 -1500);
FORCEPROP 2 LAST CDS_LIB standard
J 0
(-3000 -1500);
DISPLAY INVISIBLE (-3000 -1500);
FORCEPROP 1 LAST OFFPAGE TRUE
J 2
(-3325 -1625);
DISPLAY 0.872340 (-3325 -1625);
PAINT GREEN (-3325 -1625);
DISPLAY INVISIBLE (-3325 -1625);
FORCEPROP 1 LAST COMMENT_BODY TRUE
J 2
(-2975 -1600);
DISPLAY 0.872340 (-2975 -1600);
PAINT GREEN (-2975 -1600);
DISPLAY INVISIBLE (-2975 -1600);
FORCEPROP 2 LAST PATH I7
J 0
(-3275 -1450);
DISPLAY 1.021277 (-3275 -1450);
DISPLAY INVISIBLE (-3275 -1450);
FORCEADD UNIVERSAL_GND..1
(-2950 -1300);
FORCEPROP 3 LASTPIN (-2950 -1250) SIG_NAME AGND_HSC\g
J 0
(-2940 -1240);
DISPLAY 0.659574 (-2940 -1240);
PAINT MONO (-2940 -1240);
DISPLAY INVISIBLE (-2940 -1240);
FORCEPROP 1 LAST HDL_POWER AGND_HSC
J 1
(-2925 -1375);
DISPLAY 0.723404 (-2925 -1375);
PAINT GREEN (-2925 -1375);
FORCEPROP 2 LAST CDS_LIB logical_power
J 0
(-2950 -1300);
DISPLAY INVISIBLE (-2950 -1300);
FORCEPROP 1 LAST PATH I8
J 0
(-2875 -1300);
DISPLAY 0.872340 (-2875 -1300);
PAINT AQUA (-2875 -1300);
DISPLAY INVISIBLE (-2875 -1300);
FORCEADD OFFPAGE..4
R 2
(-2325 -1600);
FORCEPROP 2 LAST $XR2 303 
J 0
(-2847 -1600);
DISPLAY 0.638298 (-2847 -1600);
PAINT MONO (-2847 -1600);
FORCEPROP 2 LAST $XR1 302 
J 0
(-2727 -1600);
DISPLAY 0.638298 (-2727 -1600);
PAINT MONO (-2727 -1600);
FORCEPROP 2 LAST $XR0 301 
J 0
(-2607 -1600);
DISPLAY 0.638298 (-2607 -1600);
PAINT MONO (-2607 -1600);
FORCEPROP 2 LAST CDS_LIB standard
J 0
(-2325 -1600);
DISPLAY INVISIBLE (-2325 -1600);
FORCEPROP 1 LAST OFFPAGE TRUE
J 2
(-2650 -1725);
DISPLAY 0.872340 (-2650 -1725);
PAINT GREEN (-2650 -1725);
DISPLAY INVISIBLE (-2650 -1725);
FORCEPROP 1 LAST COMMENT_BODY TRUE
J 2
(-2300 -1700);
DISPLAY 0.872340 (-2300 -1700);
PAINT GREEN (-2300 -1700);
DISPLAY INVISIBLE (-2300 -1700);
FORCEPROP 2 LAST PATH I9
J 0
(-2600 -1550);
DISPLAY 1.021277 (-2600 -1550);
DISPLAY INVISIBLE (-2600 -1550);
FORCEADD DNS..2
(-2875 -2050);
PAINT RED (-2875 -2050);
FORCEPROP 2 LAST CDS_LIB mstr_misc
J 0
(-2875 -2050);
DISPLAY INVISIBLE (-2875 -2050);
FORCEPROP 1 LAST COMMENT_BODY TRUE
R 1
J 0
(-2800 -2275);
DISPLAY 0.872340 (-2800 -2275);
PAINT GREEN (-2800 -2275);
DISPLAY INVISIBLE (-2800 -2275);
FORCEADD DNS..2
(-2175 -2025);
PAINT RED (-2175 -2025);
FORCEPROP 2 LAST CDS_LIB mstr_misc
J 0
(-2175 -2025);
DISPLAY INVISIBLE (-2175 -2025);
FORCEPROP 1 LAST COMMENT_BODY TRUE
R 1
J 0
(-2100 -2250);
DISPLAY 0.872340 (-2100 -2250);
PAINT GREEN (-2100 -2250);
DISPLAY INVISIBLE (-2100 -2250);
FORCEADD DNS..2
(-2200 775);
PAINT RED (-2200 775);
FORCEPROP 2 LAST CDS_LIB mstr_misc
J 0
(-2200 775);
DISPLAY INVISIBLE (-2200 775);
FORCEPROP 1 LAST COMMENT_BODY TRUE
R 1
J 0
(-2125 550);
DISPLAY 0.872340 (-2125 550);
PAINT GREEN (-2125 550);
DISPLAY INVISIBLE (-2125 550);
FORCEADD QUANTA_TITLE_BLOCK_C..1
(4475 -3200);
FORCEPROP 0 LAST CDS_CON_LAST_MODIFIED Fri Aug 25 14:05:13 2023
J 0
(2590 -3185);
PAINT MONO (2590 -3185);
DISPLAY INVISIBLE (2590 -3185);
FORCEPROP 2 LAST CUSTOM_TXT_CDS <XR_PAGE_TITLE>
J 0
(-3415 2050);
DISPLAY 0.638298 (-3415 2050);
PAINT PINK (-3415 2050);
DISPLAY INVISIBLE (-3415 2050);
FORCEPROP 2 LAST CUSTOM_TXT_CDS <Q_NUMBER>
J 0
(3072 -3097);
DISPLAY 1.212766 (3072 -3097);
FORCEPROP 2 LAST CUSTOM_TXT_CDS <Q_PROJ>
J 0
(2093 -3098);
DISPLAY 1.212766 (2093 -3098);
FORCEPROP 2 LAST CUSTOM_TXT_CDS <CON_PAGE_NUM> OF <CON_TOTAL_PAGES>
J 0
(4029 -3182);
DISPLAY 0.978723 (4029 -3182);
FORCEPROP 2 LAST CUSTOM_TXT_CDS <Q_REV>
J 0
(4291 -3097);
DISPLAY 1.212766 (4291 -3097);
FORCEPROP 2 LAST CUSTOM_TXT_CDS <CON_LAST_MODIFIED>
J 0
(2590 -3185);
DISPLAY 0.978723 (2590 -3185);
FORCEPROP 1 LAST CUSTOM_TXT_CDS <NAME_2>
J 0
(1300 -3150);
FORCEPROP 1 LAST CUSTOM_TXT_CDS <NAME_1>
J 0
(1300 -3025);
FORCEPROP 1 LAST Q_TITLE HSC MP5990 (2/4)
J 0
(-4891 -3174);
DISPLAY 2.446809 (-4891 -3174);
PAINT GREEN (-4891 -3174);
FORCEPROP 1 LAST Q_DEPT 
J 1
(712 -3151);
DISPLAY 1.957447 (712 -3151);
PAINT GREEN (712 -3151);
FORCEPROP 2 LAST CDS_XR_PAGE_TITLE CR-302 : @S9S_MB_2U_LIB.S9S_MB_2U(SCH_1):PAGE302
J 0
(-3415 2050);
DISPLAY 0.638298 (-3415 2050);
PAINT PINK (-3415 2050);
DISPLAY INVISIBLE (-3415 2050);
FORCEPROP 1 LAST COMMENT_BODY TRUE
J 0
(4487 -3213);
DISPLAY 0.978723 (4487 -3213);
PAINT GREEN (4487 -3213);
DISPLAY INVISIBLE (4487 -3213);
FORCEPROP 2 LAST PAGE_BORDER TRUE
J 0
(-3415 2050);
DISPLAY 0.638298 (-3415 2050);
PAINT PINK (-3415 2050);
DISPLAY INVISIBLE (-3415 2050);
FORCEPROP 2 LAST CDS_LIB pure_quanta
J 0
(4475 -3200);
PAINT MONO (4475 -3200);
DISPLAY INVISIBLE (4475 -3200);
FORCEPROP 1 LAST CDS_LMAN_SYM_OUTLINE -9475,6775,100,-125
J 0
(4475 -3200);
DISPLAY 0.468085 (4475 -3200);
PAINT GREEN (4475 -3200);
DISPLAY INVISIBLE (4475 -3200);
WIRE 16 -1 (-3675 1325)(-3675 1175);
WIRE 16 -1 (-2850 1575)(-2850 1600);
WIRE 16 -1 (-2875 -2300)(-2875 -2200);
WIRE 16 -1 (-2900 525)(-2900 600);
WIRE 16 -1 (-3675 2100)(-3675 2000);
WIRE 16 -1 (-1200 -450)(-1200 -500);
WIRE 16 -1 (-3700 -1475)(-3700 -1625);
WIRE 16 -1 (-3700 -700)(-3700 -800);
WIRE 16 -1 (-2950 -1250)(-2950 -1200);
WIRE 16 -1 (-1200 2350)(-1200 2300);
WIRE 16 -1 (750 -2100)(750 -2175);
WIRE 16 -1 (875 -450)(875 -475);
WIRE 16 -1 (750 700)(750 625);
WIRE 16 -1 (875 2350)(875 2325);
WIRE 16 -1 (-2900 1300)(-2900 875);
WIRE 16 -1 (-2950 1300)(-2900 1300);
WIRE 16 -1 (-700 1300)(-2900 1300);
FORCEPROP 2 LAST SIG_NAME HSC_ON
J 0
(-1260 1310);
DISPLAY 0.808511 (-1260 1310);
WIRE 16 -1 (-2050 1600)(-700 1600);
FORCEPROP 2 LAST SIG_NAME HSC_MODE_1
J 0
(-1260 1610);
DISPLAY 0.808511 (-1260 1610);
WIRE 16 -1 (-3675 1800)(-3675 1700);
WIRE 16 -1 (-3675 1700)(-700 1700);
FORCEPROP 2 LAST SIG_NAME HSC_VDD_R_1
J 0
(-1260 1710);
DISPLAY 0.808511 (-1260 1710);
WIRE 16 -1 (-3675 1525)(-3675 1700);
WIRE 16 -1 (-1200 2300)(-900 2300);
WIRE 16 -1 (-900 2300)(-900 2250);
WIRE 16 -1 (-700 2250)(-900 2250);
WIRE 16 -1 (-900 2250)(-900 2200);
WIRE 16 -1 (-700 2200)(-900 2200);
WIRE 16 -1 (-900 2200)(-900 2150);
WIRE 16 -1 (-700 2150)(-900 2150);
WIRE 16 -1 (-900 2150)(-900 2100);
WIRE 16 -1 (-700 2100)(-900 2100);
WIRE 16 -1 (-900 2100)(-900 2050);
WIRE 16 -1 (-700 2050)(-900 2050);
WIRE 16 -1 (-700 2000)(-900 2000);
WIRE 16 -1 (-900 2050)(-900 2000);
WIRE 16 -1 (-900 2000)(-900 1950);
WIRE 16 -1 (-700 1950)(-900 1950);
WIRE 16 -1 (-900 1950)(-900 1900);
WIRE 16 -1 (-700 1900)(-900 1900);
WIRE 16 -1 (-900 1900)(-900 1850);
WIRE 16 -1 (-900 1850)(-700 1850);
WIRE 16 -1 (-2850 1600)(-2250 1600);
WIRE 16 -1 (-1675 1425)(-2225 1425);
FORCEPROP 2 LAST SIG_NAME HSC_SCREF
J 0
(-2235 1435);
DISPLAY 0.808511 (-2235 1435);
WIRE 16 -1 (375 1800)(250 1800);
WIRE 16 -1 (250 1850)(375 1850);
WIRE 16 -1 (375 1850)(375 1800);
WIRE 16 -1 (250 1900)(375 1900);
WIRE 16 -1 (375 1900)(375 1850);
WIRE 16 -1 (250 1950)(375 1950);
WIRE 16 -1 (375 1950)(375 1900);
WIRE 16 -1 (250 2000)(375 2000);
WIRE 16 -1 (375 2000)(375 1950);
WIRE 16 -1 (375 2050)(375 2000);
WIRE 16 -1 (250 2050)(375 2050);
WIRE 16 -1 (250 2100)(375 2100);
WIRE 16 -1 (375 2100)(375 2050);
WIRE 16 -1 (250 2150)(375 2150);
WIRE 16 -1 (375 2150)(375 2100);
WIRE 16 -1 (250 2200)(375 2200);
WIRE 16 -1 (375 2200)(375 2150);
WIRE 16 -1 (250 2250)(375 2250);
WIRE 16 -1 (375 2250)(375 2200);
WIRE 16 -1 (375 2325)(375 2250);
WIRE 16 -1 (875 2325)(375 2325);
WIRE 16 -1 (375 1525)(1150 1525);
WIRE 16 -1 (375 1450)(250 1450);
WIRE 16 -1 (375 1450)(375 1525);
FORCEPROP 2 LAST SIG_NAME HSC_D_OC_1
J 0
(365 1535);
DISPLAY 0.808511 (365 1535);
WIRE 16 -1 (250 1350)(1150 1350);
FORCEPROP 2 LAST SIG_NAME HSC_FLT_TYPE_1
J 0
(365 1360);
DISPLAY 0.808511 (365 1360);
WIRE 16 -1 (250 1150)(2000 1150);
FORCEPROP 2 LAST SIG_NAME HSC_FAULT
J 0
(365 1160);
DISPLAY 0.808511 (365 1160);
WIRE 16 -1 (250 1050)(2000 1050);
FORCEPROP 2 LAST SIG_NAME HSC_VTEMP
J 0
(365 1060);
DISPLAY 0.808511 (365 1060);
WIRE 16 -1 (250 950)(750 950);
FORCEPROP 2 LAST SIG_NAME HSC_SS
J 0
(365 960);
DISPLAY 0.808511 (365 960);
WIRE 16 -1 (750 950)(750 900);
WIRE 16 -1 (750 950)(2000 950);
WIRE 16 -1 (-2050 -1200)(-700 -1200);
FORCEPROP 2 LAST SIG_NAME HSC_MODE_2
J 0
(-1235 -1190);
DISPLAY 0.808511 (-1235 -1190);
WIRE 16 -1 (-1125 -1375)(-1450 -1375);
WIRE 16 -1 (-1125 -1300)(-1125 -1375);
WIRE 16 -1 (-700 -1300)(-1125 -1300);
FORCEPROP 2 LAST SIG_NAME HSC_SCREF_2
J 0
(-1235 -1290);
DISPLAY 0.808511 (-1235 -1290);
WIRE 16 -1 (-2875 -2125)(-2875 -2200);
WIRE 16 -1 (-2200 -2200)(-2875 -2200);
WIRE 16 -1 (-2200 -2125)(-2200 -2200);
WIRE 16 -1 (-2200 -2200)(-1725 -2200);
WIRE 16 -1 (-1725 -2125)(-1725 -2200);
WIRE 16 -1 (-1200 -2200)(-1725 -2200);
WIRE 16 -1 (-1200 -2125)(-1200 -2200);
WIRE 16 -1 (-1200 -2200)(-750 -2200);
WIRE 16 -1 (-750 -2000)(-750 -2200);
WIRE 16 -1 (-700 -2000)(-750 -2000);
WIRE 16 -1 (-1250 -1800)(-1200 -1800);
WIRE 16 -1 (-700 -1800)(-1200 -1800);
FORCEPROP 2 LAST SIG_NAME HSC_IMON
J 0
(-1235 -1790);
DISPLAY 0.808511 (-1235 -1790);
WIRE 16 -1 (-1200 -1925)(-1200 -1800);
WIRE 16 -1 (-1725 -1700)(-1725 -1925);
WIRE 16 -1 (-700 -1700)(-1725 -1700);
FORCEPROP 2 LAST SIG_NAME HSC_CS_2
J 0
(-1235 -1690);
DISPLAY 0.808511 (-1235 -1690);
WIRE 16 -1 (-2275 -1600)(-2200 -1600);
WIRE 16 -1 (-700 -1600)(-2200 -1600);
FORCEPROP 2 LAST SIG_NAME HSC_OCREF
J 0
(-1235 -1590);
DISPLAY 0.808511 (-1235 -1590);
WIRE 16 -1 (-2200 -1925)(-2200 -1600);
WIRE 16 -1 (-2875 -1500)(-2875 -1925);
WIRE 16 -1 (-2950 -1500)(-2875 -1500);
WIRE 16 -1 (-700 -1500)(-2875 -1500);
FORCEPROP 2 LAST SIG_NAME HSC_ON
J 0
(-1235 -1490);
DISPLAY 0.808511 (-1235 -1490);
WIRE 16 -1 (-3700 -1000)(-3700 -1100);
WIRE 16 -1 (-3700 -1100)(-700 -1100);
FORCEPROP 2 LAST SIG_NAME HSC_VDD_R_2
J 0
(-1235 -1090);
DISPLAY 0.808511 (-1235 -1090);
WIRE 16 -1 (-3700 -1275)(-3700 -1100);
WIRE 16 -1 (-900 -950)(-700 -950);
WIRE 16 -1 (-900 -900)(-900 -950);
WIRE 16 -1 (-700 -900)(-900 -900);
WIRE 16 -1 (-900 -850)(-900 -900);
WIRE 16 -1 (-700 -850)(-900 -850);
WIRE 16 -1 (-900 -800)(-900 -850);
WIRE 16 -1 (-700 -800)(-900 -800);
WIRE 16 -1 (-900 -750)(-900 -800);
WIRE 16 -1 (-700 -750)(-900 -750);
WIRE 16 -1 (-900 -700)(-900 -750);
WIRE 16 -1 (-700 -700)(-900 -700);
WIRE 16 -1 (-900 -650)(-900 -700);
WIRE 16 -1 (-700 -650)(-900 -650);
WIRE 16 -1 (-900 -600)(-900 -650);
WIRE 16 -1 (-700 -600)(-900 -600);
WIRE 16 -1 (-900 -550)(-900 -600);
WIRE 16 -1 (-700 -550)(-900 -550);
WIRE 16 -1 (-900 -500)(-900 -550);
WIRE 16 -1 (-1200 -500)(-900 -500);
WIRE 16 -1 (-700 800)(-750 800);
WIRE 16 -1 (-750 800)(-750 600);
WIRE 16 -1 (-1200 675)(-1200 600);
WIRE 16 -1 (-1200 600)(-750 600);
WIRE 16 -1 (-1725 675)(-1725 600);
WIRE 16 -1 (-1200 600)(-1725 600);
WIRE 16 -1 (-2225 675)(-2225 600);
WIRE 16 -1 (-2225 600)(-1725 600);
WIRE 16 -1 (-2225 600)(-2900 600);
WIRE 16 -1 (-2900 675)(-2900 600);
WIRE 16 -1 (-2225 875)(-2225 1200);
WIRE 16 -1 (-700 1200)(-2225 1200);
FORCEPROP 2 LAST SIG_NAME HSC_OCREF
J 0
(-1260 1210);
DISPLAY 0.808511 (-1260 1210);
WIRE 16 -1 (-2325 1200)(-2225 1200);
WIRE 16 -1 (-1725 1100)(-1725 875);
WIRE 16 -1 (-700 1100)(-1725 1100);
FORCEPROP 2 LAST SIG_NAME HSC_CS_1
J 0
(-1260 1110);
DISPLAY 0.808511 (-1260 1110);
WIRE 16 -1 (-1125 1425)(-1475 1425);
WIRE 16 -1 (-1125 1500)(-1125 1425);
WIRE 16 -1 (-700 1500)(-1125 1500);
FORCEPROP 2 LAST SIG_NAME HSC_SCREF_1
J 0
(-1260 1510);
DISPLAY 0.808511 (-1260 1510);
WIRE 16 -1 (875 -475)(375 -475);
WIRE 16 -1 (250 -550)(375 -550);
WIRE 16 -1 (375 -475)(375 -550);
WIRE 16 -1 (250 -600)(375 -600);
WIRE 16 -1 (375 -550)(375 -600);
WIRE 16 -1 (250 -650)(375 -650);
WIRE 16 -1 (375 -600)(375 -650);
WIRE 16 -1 (250 -700)(375 -700);
WIRE 16 -1 (375 -650)(375 -700);
WIRE 16 -1 (250 -750)(375 -750);
WIRE 16 -1 (375 -700)(375 -750);
WIRE 16 -1 (250 -800)(375 -800);
WIRE 16 -1 (375 -750)(375 -800);
WIRE 16 -1 (250 -850)(375 -850);
WIRE 16 -1 (375 -800)(375 -850);
WIRE 16 -1 (250 -900)(375 -900);
WIRE 16 -1 (375 -850)(375 -900);
WIRE 16 -1 (375 -1000)(250 -1000);
WIRE 16 -1 (250 -950)(375 -950);
WIRE 16 -1 (375 -900)(375 -950);
WIRE 16 -1 (375 -950)(375 -1000);
WIRE 16 -1 (-1200 875)(-1200 1000);
WIRE 16 -1 (-700 1000)(-1200 1000);
FORCEPROP 2 LAST SIG_NAME HSC_IMON
J 0
(-1260 1010);
DISPLAY 0.808511 (-1260 1010);
WIRE 16 -1 (-1250 1000)(-1200 1000);
WIRE 16 -1 (-1650 -1375)(-2225 -1375);
FORCEPROP 2 LAST SIG_NAME HSC_SCREF
J 0
(-2235 -1365);
DISPLAY 0.808511 (-2235 -1365);
WIRE 16 -1 (250 -1550)(700 -1550);
FORCEPROP 2 LAST SIG_NAME HSC_NC1_2
J 0
(365 -1540);
DISPLAY 0.808511 (365 -1540);
WIRE 16 -1 (1350 -1275)(1975 -1275);
FORCEPROP 2 LAST SIG_NAME HSC_D_OC_R
J 0
(1515 -1265);
DISPLAY 0.808511 (1515 -1265);
WIRE 16 -1 (1350 -1450)(1975 -1450);
FORCEPROP 2 LAST SIG_NAME HSC_FLT_TYPE
J 0
(1465 -1440);
DISPLAY 0.808511 (1465 -1440);
WIRE 16 -1 (1350 1350)(2000 1350);
FORCEPROP 2 LAST SIG_NAME HSC_FLT_TYPE
J 0
(1490 1360);
DISPLAY 0.808511 (1490 1360);
WIRE 16 -1 (1350 1525)(2000 1525);
FORCEPROP 2 LAST SIG_NAME HSC_D_OC_R
J 0
(1565 1535);
DISPLAY 0.808511 (1565 1535);
WIRE 16 -1 (-2950 -1200)(-2250 -1200);
WIRE 16 -1 (750 -1850)(750 -1900);
WIRE 16 -1 (750 -1850)(1975 -1850);
WIRE 16 -1 (250 -1850)(750 -1850);
FORCEPROP 2 LAST SIG_NAME HSC_SS
J 0
(340 -1840);
DISPLAY 0.808511 (340 -1840);
WIRE 16 -1 (250 -1750)(1975 -1750);
FORCEPROP 2 LAST SIG_NAME HSC_VTEMP
J 0
(340 -1740);
DISPLAY 0.808511 (340 -1740);
WIRE 16 -1 (250 -1650)(1975 -1650);
FORCEPROP 2 LAST SIG_NAME HSC_FAULT
J 0
(340 -1640);
DISPLAY 0.808511 (340 -1640);
WIRE 16 -1 (250 -1450)(1150 -1450);
FORCEPROP 2 LAST SIG_NAME HSC_FLT_TYPE_2
J 0
(340 -1440);
DISPLAY 0.808511 (340 -1440);
WIRE 16 -1 (325 -1275)(1150 -1275);
WIRE 16 -1 (325 -1350)(325 -1275);
FORCEPROP 2 LAST SIG_NAME HSC_D_OC_2
J 0
(340 -1265);
DISPLAY 0.808511 (340 -1265);
WIRE 16 -1 (325 -1350)(250 -1350);
WIRE 16 -1 (250 1250)(700 1250);
FORCEPROP 2 LAST SIG_NAME HSC_NC1_1
J 0
(365 1260);
DISPLAY 0.808511 (365 1260);
DOT 1 (-3675 1700);
DOT 1 (-900 2100);
DOT 1 (-2875 -2200);
DOT 1 (-3700 -1100);
DOT 1 (-2875 -1500);
DOT 1 (-2200 -2200);
DOT 1 (-1725 -2200);
DOT 1 (-1200 -2200);
DOT 1 (-2200 -1600);
DOT 1 (-1200 -1800);
DOT 1 (-900 -900);
DOT 1 (-900 -850);
DOT 1 (-900 -750);
DOT 1 (-900 -800);
DOT 1 (-900 -700);
DOT 1 (-900 -650);
DOT 1 (-900 -600);
DOT 1 (-900 -550);
DOT 1 (-2900 600);
DOT 1 (-2225 600);
DOT 1 (-1725 600);
DOT 1 (-2225 1200);
DOT 1 (-1200 600);
DOT 1 (-1200 1000);
DOT 1 (-900 1900);
DOT 1 (-900 2000);
DOT 1 (-900 2050);
DOT 1 (-900 2200);
DOT 1 (-900 2150);
DOT 1 (-900 2250);
DOT 1 (750 -1850);
DOT 1 (375 -900);
DOT 1 (375 -750);
DOT 1 (375 -800);
DOT 1 (375 -700);
DOT 1 (375 -650);
DOT 1 (375 -600);
DOT 1 (375 -550);
DOT 1 (750 950);
DOT 1 (375 1850);
DOT 1 (375 1950);
DOT 1 (375 2000);
DOT 1 (375 2050);
DOT 1 (375 2100);
DOT 1 (375 2200);
DOT 1 (375 2150);
DOT 1 (375 2250);
DOT 1 (-900 1950);
DOT 1 (-2900 1300);
DOT 1 (375 -850);
DOT 1 (375 -950);
DOT 1 (375 1900);
FORCENOTE
CHANGE PU287 TO AL005981A00
(-900 270) 0;
DISPLAY LEFT (-900 270);
DISPLAY 1.021277 (-900 270);
FORCENOTE
FOR MP5981:
(-900 -2495) 0;
DISPLAY LEFT (-900 -2495);
DISPLAY 1.021277 (-900 -2495);
FORCENOTE
LATCH OFF MODE
(-4725 2800) 0;
DISPLAY LEFT (-4725 2800);
DISPLAY 1.021277 (-4725 2800);
FORCENOTE
FPH=220A
(-4025 3059) 0;
DISPLAY LEFT (-4025 3059);
DISPLAY 1.595745 (-4025 3059);
FORCENOTE
20211112 MODIFY FOR GT
(-1575 3200) 0;
DISPLAY LEFT (-1575 3200);
DISPLAY 2.510638 (-1575 3200);
PAINT PINK (-1575 3200);
FORCENOTE
CHANGE PU288 TO AL005981A00
(-900 -2625) 0;
DISPLAY LEFT (-900 -2625);
DISPLAY 1.021277 (-900 -2625);
FORCENOTE
DNI PR3917, PR3921, PR3922
(-900 -2560) 0;
DISPLAY LEFT (-900 -2560);
DISPLAY 1.021277 (-900 -2560);
FORCENOTE
SOFT START TIME=6MS.
(1250 -2060) 0;
DISPLAY LEFT (1250 -2060);
DISPLAY 1.021277 (1250 -2060);
FORCENOTE
VOUT SLEW RATE: 2V/MS
(1250 -2125) 0;
DISPLAY LEFT (1250 -2125);
DISPLAY 1.021277 (1250 -2125);
FORCENOTE
DNI PR3919, PR3920, PR3916
(-900 335) 0;
DISPLAY LEFT (-900 335);
DISPLAY 1.021277 (-900 335);
FORCENOTE
FOR MP5981:
(-900 400) 0;
DISPLAY LEFT (-900 400);
DISPLAY 1.021277 (-900 400);
FORCENOTE
VOUT SLEW RATE: 2V/MS
(1250 675) 0;
DISPLAY LEFT (1250 675);
DISPLAY 1.021277 (1250 675);
FORCENOTE
SOFT START TIME=6MS.
(1250 741) 0;
DISPLAY LEFT (1250 741);
DISPLAY 1.021277 (1250 741);
FORCENOTE
ADDRESS 0X20
(-4725 2866) 0;
DISPLAY LEFT (-4725 2866);
DISPLAY 1.021277 (-4725 2866);
FORCENOTE
UV =10.091V
(-4725 2925) 0;
DISPLAY LEFT (-4725 2925);
DISPLAY 1.021277 (-4725 2925);
FORCENOTE
OV =14.333V
(-4725 2975) 0;
DISPLAY LEFT (-4725 2975);
DISPLAY 1.021277 (-4725 2975);
FORCENOTE
OCW=220A
(-4750 3059) 0;
DISPLAY LEFT (-4750 3059);
DISPLAY 1.595745 (-4750 3059);
FORCENOTE
OCP=240A
(-4750 3134) 0;
DISPLAY LEFT (-4750 3134);
DISPLAY 1.595745 (-4750 3134);
FORCENOTE
HOT SWAT CIRCUIT
(-4746 3238) 0;
DISPLAY LEFT (-4746 3238);
DISPLAY 2.000000 (-4746 3238);
QUIT
